FILE_TYPE = MACRO_DRAWING;
SET COLOR_WIRE YELLOW;
SET COLOR_PROP ORANGE;
SET COLOR_DOT WHITE;
SET COLOR_ARC YELLOW;
SET COLOR_BODY GREEN;
SET COLOR_NOTE PURPLE;
SET PROP_DISPLAY VALUE;
SET PAGE_NUMBER P194;
FORCEADD UNIVERSAL_GND..1
(-500 -2900);
FORCEPROP 3 LASTPIN (-500 -2850) SIG_NAME GND\g
J 0
(-490 -2840);
DISPLAY 0.659574 (-490 -2840);
PAINT MONO (-490 -2840);
DISPLAY INVISIBLE (-490 -2840);
FORCEPROP 2 LAST CDS_LIB logical_power
J 0
(-500 -2900);
DISPLAY INVISIBLE (-500 -2900);
FORCEPROP 1 LAST HDL_POWER GND
J 1
(-475 -2975);
DISPLAY 0.872340 (-475 -2975);
PAINT GREEN (-475 -2975);
DISPLAY INVISIBLE (-475 -2975);
FORCEPROP 1 LAST PATH I1
J 0
(-425 -2900);
DISPLAY 0.872340 (-425 -2900);
PAINT AQUA (-425 -2900);
DISPLAY INVISIBLE (-425 -2900);
FORCEADD UNIVERSAL_POWER..1
R 2
(-3500 1025);
FORCEPROP 3 LASTPIN (-3500 975) SIG_NAME P3V3_AUX\g
J 0
(-3490 985);
DISPLAY 0.659574 (-3490 985);
PAINT MONO (-3490 985);
DISPLAY INVISIBLE (-3490 985);
FORCEPROP 1 LAST HDL_POWER P3V3_AUX
J 1
(-3500 1075);
DISPLAY 0.723404 (-3500 1075);
PAINT GREEN (-3500 1075);
FORCEPROP 2 LAST CDS_LIB logical_power
J 0
(-3500 1025);
DISPLAY INVISIBLE (-3500 1025);
FORCEPROP 1 LAST PATH I10
J 2
(-3550 1050);
DISPLAY 0.872340 (-3550 1050);
PAINT AQUA (-3550 1050);
DISPLAY INVISIBLE (-3550 1050);
FORCEADD OFFPAGE..1
(-2875 975);
PAINT AQUA (-2875 975);
FORCEPROP 2 LAST $XR1 152 
J 0
(-3277 975);
DISPLAY 0.638298 (-3277 975);
PAINT MONO (-3277 975);
FORCEPROP 2 LAST $XR0 227 
J 0
(-3157 975);
DISPLAY 0.638298 (-3157 975);
PAINT MONO (-3157 975);
FORCEPROP 2 LAST CDS_LIB standard
J 0
(-2875 975);
DISPLAY INVISIBLE (-2875 975);
FORCEPROP 1 LAST OFFPAGE TRUE
J 0
(-2550 850);
DISPLAY 0.872340 (-2550 850);
PAINT AQUA (-2550 850);
DISPLAY INVISIBLE (-2550 850);
FORCEPROP 1 LAST COMMENT_BODY TRUE
J 0
(-2750 875);
DISPLAY 0.872340 (-2750 875);
PAINT GREEN (-2750 875);
DISPLAY INVISIBLE (-2750 875);
FORCEPROP 2 LAST PATH I11
J 0
(-3125 1025);
DISPLAY 1.021277 (-3125 1025);
DISPLAY INVISIBLE (-3125 1025);
FORCEADD OFFPAGE..5
R 2
(-2375 175);
PAINT AQUA (-2375 175);
FORCEPROP 2 LAST $XR0 196 
J 0
(-2186 175);
DISPLAY 0.638298 (-2186 175);
PAINT MONO (-2186 175);
FORCEPROP 2 LAST CDS_LIB standard
J 2
(-2375 175);
DISPLAY INVISIBLE (-2375 175);
FORCEPROP 1 LAST OFFPAGE TRUE
J 2
(-2700 50);
DISPLAY 0.872340 (-2700 50);
PAINT AQUA (-2700 50);
DISPLAY INVISIBLE (-2700 50);
FORCEPROP 1 LAST COMMENT_BODY TRUE
J 2
(-2475 100);
DISPLAY 1.170213 (-2475 100);
PAINT GREEN (-2475 100);
DISPLAY INVISIBLE (-2475 100);
FORCEPROP 2 LAST PATH I12
J 0
(-2175 225);
DISPLAY 1.021277 (-2175 225);
DISPLAY INVISIBLE (-2175 225);
FORCEADD Q_RES..1
(-2075 975);
FORCEPROP 1 LAST PART_NUMBER CS03322FB03
J 0
(-1825 925);
DISPLAY 0.723404 (-1825 925);
DISPLAY INVISIBLE (-1825 925);
FORCEPROP 1 LAST MATERIAL EMPTY
J 0
(-2000 925);
DISPLAY 0.723404 (-2000 925);
FORCEPROP 1 LAST PACK_TYPE 0402LF
J 0
(-2225 925);
DISPLAY 0.723404 (-2225 925);
FORCEPROP 1 LAST TOLERANCE 1%
J 0
(-2325 925);
DISPLAY 0.723404 (-2325 925);
FORCEPROP 1 LAST WATTAGE 1/16W
J 2
(-2350 925);
DISPLAY 0.723404 (-2350 925);
FORCEPROP 1 LAST VALUE 33.2
J 2
(-1875 975);
DISPLAY 0.723404 (-1875 975);
FORCEPROP 1 LAST $LOCATION R4451
J 0
(-2325 975);
DISPLAY 0.723404 (-2325 975);
FORCEPROP 2 LAST CDS_LIB pure_quanta
J 0
(-2075 975);
DISPLAY INVISIBLE (-2075 975);
FORCEPROP 1 LAST PATH I13
J 0
(-2125 1125);
DISPLAY 0.978723 (-2125 1125);
PAINT WHITE (-2125 1125);
DISPLAY INVISIBLE (-2125 1125);
FORCEPROP 2 LAST CDS_LOCATION R4451
J 0
(-2125 1175);
DISPLAY 1.021277 (-2125 1175);
DISPLAY INVISIBLE (-2125 1175);
FORCEPROP 0 LAST $SEC 1
J 0
(-2375 1050);
DISPLAY INVISIBLE (-2375 1050);
FORCEPROP 0 LAST CDS_SEC 1
J 0
(-2375 1050);
DISPLAY INVISIBLE (-2375 1050);
FORCEPROP 1 LASTPIN (-2175 975) $PN 1
J 0
(-2163 987);
DISPLAY 0.787234 (-2163 987);
PAINT MONO (-2163 987);
DISPLAY INVISIBLE (-2163 987);
FORCEPROP 1 LASTPIN (-1975 975) $PN 2
J 0
(-2013 987);
DISPLAY 0.787234 (-2013 987);
PAINT MONO (-2013 987);
DISPLAY INVISIBLE (-2013 987);
FORCEADD UNIVERSAL_GND..1
(-1625 400);
FORCEPROP 3 LASTPIN (-1625 450) SIG_NAME GND\g
J 0
(-1615 460);
DISPLAY 0.659574 (-1615 460);
PAINT MONO (-1615 460);
DISPLAY INVISIBLE (-1615 460);
FORCEPROP 2 LAST CDS_LIB logical_power
J 0
(-1625 400);
DISPLAY INVISIBLE (-1625 400);
FORCEPROP 1 LAST HDL_POWER GND
J 1
(-1600 325);
DISPLAY 0.872340 (-1600 325);
PAINT GREEN (-1600 325);
DISPLAY INVISIBLE (-1600 325);
FORCEPROP 1 LAST PATH I14
J 0
(-1550 400);
DISPLAY 0.872340 (-1550 400);
PAINT AQUA (-1550 400);
DISPLAY INVISIBLE (-1550 400);
FORCEADD Q_CAP..1
(-1625 700);
FORCEPROP 1 LAST PART_NUMBER CH5104KEB02
J 0
(-1575 550);
DISPLAY 0.574468 (-1575 550);
DISPLAY INVISIBLE (-1575 550);
FORCEPROP 1 LAST VALUE 1UF
J 0
(-1575 750);
DISPLAY 0.574468 (-1575 750);
FORCEPROP 1 LAST VOLTAGE 25V
J 0
(-1575 700);
DISPLAY 0.574468 (-1575 700);
FORCEPROP 1 LAST TOLERANCE 10%
J 0
(-1575 650);
DISPLAY 0.574468 (-1575 650);
FORCEPROP 1 LAST MATERIAL EMPTY
J 0
(-1575 600);
DISPLAY 0.574468 (-1575 600);
FORCEPROP 1 LAST PACK_TYPE C0402
J 0
(-1575 500);
DISPLAY 0.574468 (-1575 500);
FORCEPROP 1 LAST $LOCATION C2317
J 0
(-1575 800);
DISPLAY 0.978723 (-1575 800);
FORCEPROP 1 LASTPIN (-1625 800) $PN 1
J 0
(-1615 780);
DISPLAY 0.787234 (-1615 780);
PAINT MONO (-1615 780);
FORCEPROP 1 LASTPIN (-1625 600) $PN 2
J 0
(-1615 580);
DISPLAY 0.787234 (-1615 580);
PAINT MONO (-1615 580);
FORCEPROP 2 LAST CDS_LIB pure_quanta
J 0
(-1625 700);
DISPLAY INVISIBLE (-1625 700);
FORCEPROP 1 LAST PATH I15
J 0
(-1575 850);
DISPLAY 0.978723 (-1575 850);
PAINT WHITE (-1575 850);
DISPLAY INVISIBLE (-1575 850);
FORCEPROP 0 LAST CDS_LOCATION C2317
J 0
(-1575 850);
DISPLAY 1.021277 (-1575 850);
DISPLAY INVISIBLE (-1575 850);
FORCEPROP 0 LAST $SEC 1
J 0
(-1575 850);
DISPLAY 0.680851 (-1575 850);
PAINT MONO (-1575 850);
DISPLAY INVISIBLE (-1575 850);
FORCEPROP 0 LAST CDS_SEC 1
J 0
(-1575 850);
DISPLAY 1.021277 (-1575 850);
DISPLAY INVISIBLE (-1575 850);
FORCEADD Q_RES..1
(-1550 -2275);
FORCEPROP 1 LAST PART_NUMBER CS00002JB13
J 0
(-1825 -2400);
DISPLAY 0.723404 (-1825 -2400);
PAINT WHITE (-1825 -2400);
DISPLAY INVISIBLE (-1825 -2400);
FORCEPROP 1 LAST PACK_TYPE 0402LF
J 0
(-2050 -2275);
DISPLAY 0.723404 (-2050 -2275);
FORCEPROP 1 LAST VALUE 0
J 2
(-1400 -2275);
DISPLAY 0.723404 (-1400 -2275);
FORCEPROP 1 LAST MATERIAL EMPTY
J 0
(-2225 -2275);
DISPLAY 0.723404 (-2225 -2275);
PAINT RED (-2225 -2275);
FORCEPROP 1 LAST $LOCATION R4455
J 0
(-1775 -2275);
DISPLAY 0.723404 (-1775 -2275);
FORCEPROP 1 LASTPIN (-1650 -2275) $PN 1
J 0
(-1638 -2263);
DISPLAY 0.787234 (-1638 -2263);
PAINT MONO (-1638 -2263);
FORCEPROP 1 LASTPIN (-1450 -2275) $PN 2
J 0
(-1488 -2263);
DISPLAY 0.787234 (-1488 -2263);
PAINT MONO (-1488 -2263);
FORCEPROP 2 LAST CDS_LIB pure_quanta
J 0
(-1550 -2275);
DISPLAY INVISIBLE (-1550 -2275);
FORCEPROP 1 LAST WATTAGE 1/16W
J 2
(-1475 -2350);
DISPLAY 0.723404 (-1475 -2350);
PAINT SKYBLUE (-1475 -2350);
DISPLAY INVISIBLE (-1475 -2350);
FORCEPROP 1 LAST TOLERANCE 5%
J 0
(-1750 -2350);
DISPLAY 0.723404 (-1750 -2350);
PAINT SKYBLUE (-1750 -2350);
DISPLAY INVISIBLE (-1750 -2350);
FORCEPROP 1 LAST PATH I16
J 0
(-1600 -2125);
DISPLAY 0.978723 (-1600 -2125);
PAINT WHITE (-1600 -2125);
DISPLAY INVISIBLE (-1600 -2125);
FORCEPROP 2 LAST CDS_LOCATION R4455
J 0
(-1600 -2075);
DISPLAY 1.021277 (-1600 -2075);
DISPLAY INVISIBLE (-1600 -2075);
FORCEPROP 2 LAST $SEC 1
J 0
(-1600 -2075);
DISPLAY 0.680851 (-1600 -2075);
PAINT MONO (-1600 -2075);
DISPLAY INVISIBLE (-1600 -2075);
FORCEPROP 2 LAST CDS_SEC 1
J 0
(-1600 -2075);
DISPLAY 1.021277 (-1600 -2075);
DISPLAY INVISIBLE (-1600 -2075);
FORCEADD Q_RES..1
(-1550 -2225);
FORCEPROP 1 LAST PART_NUMBER CS00002JB13
J 0
(-1825 -2350);
DISPLAY 0.723404 (-1825 -2350);
PAINT WHITE (-1825 -2350);
DISPLAY INVISIBLE (-1825 -2350);
FORCEPROP 1 LAST MATERIAL EMPTY
J 0
(-2225 -2225);
DISPLAY 0.723404 (-2225 -2225);
PAINT RED (-2225 -2225);
FORCEPROP 1 LAST VALUE 0
J 2
(-1400 -2225);
DISPLAY 0.723404 (-1400 -2225);
FORCEPROP 1 LAST PACK_TYPE 0402LF
J 0
(-2050 -2225);
DISPLAY 0.723404 (-2050 -2225);
FORCEPROP 1 LAST $LOCATION R4454
J 0
(-1775 -2225);
DISPLAY 0.723404 (-1775 -2225);
FORCEPROP 1 LASTPIN (-1650 -2225) $PN 1
J 0
(-1638 -2213);
DISPLAY 0.787234 (-1638 -2213);
PAINT MONO (-1638 -2213);
FORCEPROP 1 LASTPIN (-1450 -2225) $PN 2
J 0
(-1488 -2213);
DISPLAY 0.787234 (-1488 -2213);
PAINT MONO (-1488 -2213);
FORCEPROP 2 LAST CDS_LIB pure_quanta
J 0
(-1550 -2225);
DISPLAY INVISIBLE (-1550 -2225);
FORCEPROP 1 LAST WATTAGE 1/16W
J 2
(-1475 -2300);
DISPLAY 0.723404 (-1475 -2300);
PAINT SKYBLUE (-1475 -2300);
DISPLAY INVISIBLE (-1475 -2300);
FORCEPROP 1 LAST TOLERANCE 5%
J 0
(-1750 -2300);
DISPLAY 0.723404 (-1750 -2300);
PAINT SKYBLUE (-1750 -2300);
DISPLAY INVISIBLE (-1750 -2300);
FORCEPROP 1 LAST PATH I17
J 0
(-1600 -2075);
DISPLAY 0.978723 (-1600 -2075);
PAINT WHITE (-1600 -2075);
DISPLAY INVISIBLE (-1600 -2075);
FORCEPROP 2 LAST CDS_LOCATION R4454
J 0
(-1600 -2025);
DISPLAY 1.021277 (-1600 -2025);
DISPLAY INVISIBLE (-1600 -2025);
FORCEPROP 2 LAST $SEC 1
J 0
(-1600 -2025);
DISPLAY 0.680851 (-1600 -2025);
PAINT MONO (-1600 -2025);
DISPLAY INVISIBLE (-1600 -2025);
FORCEPROP 2 LAST CDS_SEC 1
J 0
(-1600 -2025);
DISPLAY 1.021277 (-1600 -2025);
DISPLAY INVISIBLE (-1600 -2025);
FORCEADD Q_RES..2
(-1350 -2100);
FORCEPROP 1 LAST PART_NUMBER CS00002JB13
J 0
(-1725 -2125);
DISPLAY 0.638298 (-1725 -2125);
DISPLAY INVISIBLE (-1725 -2125);
FORCEPROP 1 LAST TOLERANCE 5%
J 0
(-1450 -1975);
DISPLAY 0.638298 (-1450 -1975);
FORCEPROP 1 LAST VALUE 0
J 0
(-1425 -1925);
DISPLAY 0.638298 (-1425 -1925);
FORCEPROP 1 LAST MATERIAL CHIP
J 0
(-1525 -2075);
DISPLAY 0.638298 (-1525 -2075);
FORCEPROP 1 LAST PACK_TYPE 0402LF
J 0
(-1550 -2175);
DISPLAY 0.638298 (-1550 -2175);
FORCEPROP 1 LAST WATTAGE 1/16W
J 0
(-1550 -2025);
DISPLAY 0.638298 (-1550 -2025);
FORCEPROP 1 LAST $LOCATION R4460
J 0
(-1500 -1875);
DISPLAY 0.638298 (-1500 -1875);
FORCEPROP 1 LASTPIN (-1350 -2000) $PN 1
J 0
(-1345 -2038);
DISPLAY 0.787234 (-1345 -2038);
PAINT MONO (-1345 -2038);
FORCEPROP 1 LASTPIN (-1350 -2200) $PN 2
J 0
(-1345 -2190);
DISPLAY 0.787234 (-1345 -2190);
PAINT MONO (-1345 -2190);
FORCEPROP 2 LAST CDS_LIB pure_quanta
J 0
(-1350 -2100);
DISPLAY INVISIBLE (-1350 -2100);
FORCEPROP 1 LAST PATH I18
J 0
(-1300 -1925);
DISPLAY 0.978723 (-1300 -1925);
PAINT WHITE (-1300 -1925);
DISPLAY INVISIBLE (-1300 -1925);
FORCEPROP 2 LAST CDS_LOCATION R4460
J 0
(-1300 -1875);
DISPLAY 1.021277 (-1300 -1875);
DISPLAY INVISIBLE (-1300 -1875);
FORCEPROP 2 LAST $SEC 1
J 0
(-1300 -1875);
DISPLAY 0.680851 (-1300 -1875);
PAINT MONO (-1300 -1875);
DISPLAY INVISIBLE (-1300 -1875);
FORCEPROP 2 LAST CDS_SEC 1
J 0
(-1300 -1875);
DISPLAY 1.021277 (-1300 -1875);
DISPLAY INVISIBLE (-1300 -1875);
FORCEADD Q_RES..2
(-1275 -2100);
FORCEPROP 1 LAST PART_NUMBER CS00002JB13
J 0
(-1255 -2150);
DISPLAY 0.510638 (-1255 -2150);
DISPLAY INVISIBLE (-1255 -2150);
FORCEPROP 1 LAST VALUE 0
J 0
(-1250 -2050);
DISPLAY 0.510638 (-1250 -2050);
FORCEPROP 1 LAST MATERIAL CHIP
J 0
(-1250 -2150);
DISPLAY 0.510638 (-1250 -2150);
FORCEPROP 1 LAST $LOCATION R4461
J 0
(-1250 -2100);
DISPLAY 0.510638 (-1250 -2100);
FORCEPROP 1 LASTPIN (-1275 -2000) $PN 1
J 0
(-1270 -2038);
DISPLAY 0.787234 (-1270 -2038);
PAINT MONO (-1270 -2038);
FORCEPROP 1 LASTPIN (-1275 -2200) $PN 2
J 0
(-1285 -2190);
DISPLAY 0.787234 (-1285 -2190);
PAINT MONO (-1285 -2190);
FORCEPROP 1 LAST WATTAGE 1/16W
J 0
(-1255 -2050);
DISPLAY 0.510638 (-1255 -2050);
DISPLAY INVISIBLE (-1255 -2050);
FORCEPROP 1 LAST TOLERANCE 5%
J 0
(-1250 -2000);
DISPLAY 0.510638 (-1250 -2000);
DISPLAY INVISIBLE (-1250 -2000);
FORCEPROP 1 LAST PACK_TYPE 0402LF
J 0
(-1255 -2200);
DISPLAY 0.510638 (-1255 -2200);
DISPLAY INVISIBLE (-1255 -2200);
FORCEPROP 2 LAST CDS_LIB pure_quanta
J 0
(-1275 -2100);
DISPLAY INVISIBLE (-1275 -2100);
FORCEPROP 1 LAST PATH I19
J 0
(-1225 -1925);
DISPLAY 0.978723 (-1225 -1925);
PAINT WHITE (-1225 -1925);
DISPLAY INVISIBLE (-1225 -1925);
FORCEPROP 2 LAST CDS_LOCATION R4461
J 0
(-1225 -1875);
DISPLAY 1.021277 (-1225 -1875);
DISPLAY INVISIBLE (-1225 -1875);
FORCEPROP 2 LAST $SEC 1
J 0
(-1225 -1875);
DISPLAY 0.680851 (-1225 -1875);
PAINT MONO (-1225 -1875);
DISPLAY INVISIBLE (-1225 -1875);
FORCEPROP 2 LAST CDS_SEC 1
J 0
(-1225 -1875);
DISPLAY 1.021277 (-1225 -1875);
DISPLAY INVISIBLE (-1225 -1875);
FORCEADD Q_CAP..1
(-500 -2675);
FORCEPROP 1 LAST PART_NUMBER CH4104K1B00
J 0
(-450 -2825);
DISPLAY 0.723404 (-450 -2825);
PAINT WHITE (-450 -2825);
DISPLAY INVISIBLE (-450 -2825);
FORCEPROP 1 LAST VALUE 0.1UF
J 0
(-450 -2625);
DISPLAY 0.723404 (-450 -2625);
PAINT SKYBLUE (-450 -2625);
FORCEPROP 1 LAST MATERIAL EMPTY
J 0
(-450 -2775);
DISPLAY 0.723404 (-450 -2775);
PAINT SKYBLUE (-450 -2775);
FORCEPROP 1 LAST TOLERANCE 10%
J 0
(-450 -2725);
DISPLAY 0.723404 (-450 -2725);
PAINT SKYBLUE (-450 -2725);
FORCEPROP 1 LAST VOLTAGE 25V
J 0
(-450 -2675);
DISPLAY 0.723404 (-450 -2675);
PAINT SKYBLUE (-450 -2675);
FORCEPROP 1 LAST PACK_TYPE 0402
J 0
(-450 -2875);
DISPLAY 0.723404 (-450 -2875);
PAINT SKYBLUE (-450 -2875);
FORCEPROP 1 LAST $LOCATION C2321
J 0
(-450 -2575);
DISPLAY 0.723404 (-450 -2575);
PAINT AQUA (-450 -2575);
FORCEPROP 1 LASTPIN (-500 -2575) $PN 1
J 0
(-490 -2595);
DISPLAY 0.723404 (-490 -2595);
PAINT MONO (-490 -2595);
FORCEPROP 1 LASTPIN (-500 -2775) $PN 2
J 0
(-490 -2795);
DISPLAY 0.723404 (-490 -2795);
PAINT MONO (-490 -2795);
FORCEPROP 2 LAST CDS_LIB pure_quanta
J 0
(-500 -2675);
DISPLAY INVISIBLE (-500 -2675);
FORCEPROP 1 LAST PATH I2
J 0
(-450 -2525);
DISPLAY 0.978723 (-450 -2525);
PAINT WHITE (-450 -2525);
DISPLAY INVISIBLE (-450 -2525);
FORCEPROP 2 LAST CDS_LOCATION C2321
J 0
(-450 -2575);
DISPLAY 0.723404 (-450 -2575);
PAINT AQUA (-450 -2575);
DISPLAY INVISIBLE (-450 -2575);
FORCEPROP 2 LAST $SEC 1
J 0
(-450 -2475);
DISPLAY 0.680851 (-450 -2475);
PAINT MONO (-450 -2475);
DISPLAY INVISIBLE (-450 -2475);
FORCEPROP 0 LAST CDS_SEC 1
J 0
(-450 -2525);
DISPLAY INVISIBLE (-450 -2525);
FORCEADD TUSB211IRWBR..1
(525 -2350);
FORCEPROP 1 LAST PART_NUMBER AL000211007
J 0
(298 -2102);
DISPLAY 0.723404 (298 -2102);
PAINT WHITE (298 -2102);
DISPLAY INVISIBLE (298 -2102);
FORCEPROP 1 LAST MATERIAL EMPTY
J 0
(298 -2171);
DISPLAY 0.723404 (298 -2171);
PAINT SKYBLUE (298 -2171);
FORCEPROP 2 LAST PART_TYPE SMLF
J 0
(300 -1925);
DISPLAY 1.021277 (300 -1925);
FORCEPROP 2 LAST VALUE TUSB211IRWBR
J 0
(300 -1975);
DISPLAY 0.723404 (300 -1975);
PAINT SKYBLUE (300 -1975);
FORCEPROP 1 LAST $LOCATION U312
J 0
(298 -2026);
DISPLAY 0.723404 (298 -2026);
PAINT AQUA (298 -2026);
FORCEPROP 0 LASTPIN (150 -2375) $PN 4
J 2
(140 -2365);
DISPLAY 0.808511 (140 -2365);
FORCEPROP 0 LASTPIN (150 -2275) $PN 1
J 2
(140 -2265);
DISPLAY 0.808511 (140 -2265);
FORCEPROP 0 LASTPIN (150 -2225) $PN 2
J 2
(140 -2215);
DISPLAY 0.808511 (140 -2215);
FORCEPROP 0 LASTPIN (900 -2275) $PN 8
J 0
(910 -2265);
DISPLAY 0.808511 (910 -2265);
FORCEPROP 0 LASTPIN (900 -2225) $PN 7
J 0
(910 -2215);
DISPLAY 0.808511 (910 -2215);
FORCEPROP 0 LASTPIN (900 -2475) $PN 9
J 0
(910 -2465);
DISPLAY 0.808511 (910 -2465);
FORCEPROP 0 LASTPIN (150 -2475) $PN 6
J 2
(140 -2465);
DISPLAY 0.808511 (140 -2465);
FORCEPROP 0 LASTPIN (900 -2425) $PN 10
J 0
(910 -2415);
DISPLAY 0.808511 (910 -2415);
FORCEPROP 0 LASTPIN (150 -2425) $PN 5
J 2
(140 -2415);
DISPLAY 0.808511 (140 -2415);
FORCEPROP 0 LASTPIN (150 -2325) $PN 3
J 2
(140 -2315);
DISPLAY 0.808511 (140 -2315);
FORCEPROP 0 LASTPIN (900 -2325) $PN 12
J 0
(910 -2315);
DISPLAY 0.808511 (910 -2315);
FORCEPROP 0 LASTPIN (900 -2375) $PN 11
J 0
(910 -2365);
DISPLAY 0.808511 (910 -2365);
FORCEPROP 2 LAST CDS_LIB pure_quanta
J 0
(525 -2350);
DISPLAY INVISIBLE (525 -2350);
FORCEPROP 1 LAST CDS_LMAN_SYM_OUTLINE -225,175,225,-175
J 0
(525 -2350);
DISPLAY 0.468085 (525 -2350);
PAINT GREEN (525 -2350);
DISPLAY INVISIBLE (525 -2350);
FORCEPROP 1 LAST NEEDS_NO_SIZE TRUE
J 0
(750 -2468);
DISPLAY 0.723404 (750 -2468);
PAINT GREEN (750 -2468);
DISPLAY INVISIBLE (750 -2468);
FORCEPROP 1 LAST PATH I20
J 0
(750 -2525);
DISPLAY 0.723404 (750 -2525);
PAINT GREEN (750 -2525);
DISPLAY INVISIBLE (750 -2525);
FORCEPROP 0 LAST CDS_LOCATION U312
J 0
(300 -1875);
DISPLAY INVISIBLE (300 -1875);
FORCEPROP 0 LAST $SEC 1
J 0
(300 -1875);
DISPLAY INVISIBLE (300 -1875);
FORCEPROP 0 LAST CDS_SEC 1
J 0
(300 -1875);
DISPLAY INVISIBLE (300 -1875);
FORCEADD UNIVERSAL_POWER..1
R 2
(-1525 75);
FORCEPROP 3 LASTPIN (-1525 25) SIG_NAME P3V3_AUX\g
J 0
(-1515 35);
DISPLAY 0.659574 (-1515 35);
PAINT MONO (-1515 35);
DISPLAY INVISIBLE (-1515 35);
FORCEPROP 1 LAST HDL_POWER P3V3_AUX
J 1
(-1525 125);
DISPLAY 0.723404 (-1525 125);
PAINT GREEN (-1525 125);
FORCEPROP 2 LAST CDS_LIB logical_power
J 0
(-1525 75);
DISPLAY INVISIBLE (-1525 75);
FORCEPROP 1 LAST PATH I21
J 2
(-1575 100);
DISPLAY 0.872340 (-1575 100);
PAINT AQUA (-1575 100);
DISPLAY INVISIBLE (-1575 100);
FORCEADD Q_RES..1
(-900 -575);
FORCEPROP 1 LAST PART_NUMBER CS31002FB08
J 0
(-1075 -725);
DISPLAY 0.638298 (-1075 -725);
DISPLAY INVISIBLE (-1075 -725);
FORCEPROP 1 LAST MATERIAL EMPTY
J 0
(-900 -675);
DISPLAY 0.638298 (-900 -675);
PAINT RED (-900 -675);
FORCEPROP 1 LAST PACK_TYPE 0402LF
J 0
(-800 -625);
DISPLAY 0.638298 (-800 -625);
FORCEPROP 1 LAST TOLERANCE 1%
J 0
(-900 -625);
DISPLAY 0.638298 (-900 -625);
FORCEPROP 1 LAST VALUE 10K
J 2
(-925 -625);
DISPLAY 0.638298 (-925 -625);
FORCEPROP 1 LAST WATTAGE 1/16W
J 2
(-925 -675);
DISPLAY 0.638298 (-925 -675);
FORCEPROP 1 LAST $LOCATION R4459
J 0
(-1075 -600);
DISPLAY 0.638298 (-1075 -600);
FORCEPROP 1 LASTPIN (-1000 -575) $PN 1
J 0
(-988 -563);
DISPLAY 0.787234 (-988 -563);
PAINT MONO (-988 -563);
FORCEPROP 1 LASTPIN (-800 -575) $PN 2
J 0
(-838 -563);
DISPLAY 0.787234 (-838 -563);
PAINT MONO (-838 -563);
FORCEPROP 2 LAST CDS_LIB pure_quanta
J 0
(-900 -575);
DISPLAY INVISIBLE (-900 -575);
FORCEPROP 1 LAST PATH I22
J 0
(-950 -425);
DISPLAY 0.978723 (-950 -425);
PAINT WHITE (-950 -425);
DISPLAY INVISIBLE (-950 -425);
FORCEPROP 0 LAST CDS_LOCATION R4459
J 0
(-1050 -525);
DISPLAY 1.021277 (-1050 -525);
DISPLAY INVISIBLE (-1050 -525);
FORCEPROP 0 LAST $SEC 1
J 0
(-1050 -525);
DISPLAY 0.680851 (-1050 -525);
PAINT MONO (-1050 -525);
DISPLAY INVISIBLE (-1050 -525);
FORCEPROP 0 LAST CDS_SEC 1
J 0
(-1050 -525);
DISPLAY 1.021277 (-1050 -525);
DISPLAY INVISIBLE (-1050 -525);
FORCEADD Q_RES..1
(-900 -450);
FORCEPROP 1 LAST PART_NUMBER CS31002FB08
J 0
(-1075 -600);
DISPLAY 0.638298 (-1075 -600);
DISPLAY INVISIBLE (-1075 -600);
FORCEPROP 1 LAST VALUE 10K
J 2
(-925 -500);
DISPLAY 0.638298 (-925 -500);
FORCEPROP 1 LAST MATERIAL EMPTY
J 0
(-875 -500);
DISPLAY 0.638298 (-875 -500);
PAINT RED (-875 -500);
FORCEPROP 1 LAST $LOCATION R4458
J 0
(-1075 -450);
DISPLAY 0.638298 (-1075 -450);
FORCEPROP 1 LASTPIN (-1000 -450) $PN 1
J 0
(-988 -438);
DISPLAY 0.787234 (-988 -438);
PAINT MONO (-988 -438);
FORCEPROP 1 LASTPIN (-800 -450) $PN 2
J 0
(-838 -438);
DISPLAY 0.787234 (-838 -438);
PAINT MONO (-838 -438);
FORCEPROP 1 LAST WATTAGE 1/16W
J 2
(-925 -550);
DISPLAY 0.638298 (-925 -550);
DISPLAY INVISIBLE (-925 -550);
FORCEPROP 1 LAST TOLERANCE 1%
J 0
(-900 -500);
DISPLAY 0.638298 (-900 -500);
DISPLAY INVISIBLE (-900 -500);
FORCEPROP 1 LAST PACK_TYPE 0402LF
J 0
(-800 -500);
DISPLAY 0.638298 (-800 -500);
DISPLAY INVISIBLE (-800 -500);
FORCEPROP 2 LAST CDS_LIB pure_quanta
J 0
(-900 -450);
DISPLAY INVISIBLE (-900 -450);
FORCEPROP 1 LAST PATH I23
J 0
(-950 -300);
DISPLAY 0.978723 (-950 -300);
PAINT WHITE (-950 -300);
DISPLAY INVISIBLE (-950 -300);
FORCEPROP 0 LAST CDS_LOCATION R4458
J 0
(-1050 -375);
DISPLAY 1.021277 (-1050 -375);
DISPLAY INVISIBLE (-1050 -375);
FORCEPROP 0 LAST $SEC 1
J 0
(-1050 -375);
DISPLAY 0.680851 (-1050 -375);
PAINT MONO (-1050 -375);
DISPLAY INVISIBLE (-1050 -375);
FORCEPROP 0 LAST CDS_SEC 1
J 0
(-1050 -375);
DISPLAY 1.021277 (-1050 -375);
DISPLAY INVISIBLE (-1050 -375);
FORCEADD Q_RES..1
(-900 -325);
FORCEPROP 1 LAST PART_NUMBER CS31002FB08
J 0
(-1075 -475);
DISPLAY 0.638298 (-1075 -475);
DISPLAY INVISIBLE (-1075 -475);
FORCEPROP 1 LAST MATERIAL EMPTY
J 0
(-875 -375);
DISPLAY 0.638298 (-875 -375);
PAINT RED (-875 -375);
FORCEPROP 1 LAST VALUE 10K
J 2
(-925 -375);
DISPLAY 0.638298 (-925 -375);
FORCEPROP 1 LAST $LOCATION R4457
J 0
(-1075 -325);
DISPLAY 0.638298 (-1075 -325);
FORCEPROP 1 LASTPIN (-1000 -325) $PN 1
J 0
(-988 -313);
DISPLAY 0.787234 (-988 -313);
PAINT MONO (-988 -313);
FORCEPROP 1 LASTPIN (-800 -325) $PN 2
J 0
(-838 -313);
DISPLAY 0.787234 (-838 -313);
PAINT MONO (-838 -313);
FORCEPROP 2 LAST CDS_LIB pure_quanta
J 0
(-900 -325);
DISPLAY INVISIBLE (-900 -325);
FORCEPROP 1 LAST WATTAGE 1/16W
J 2
(-925 -425);
DISPLAY 0.638298 (-925 -425);
DISPLAY INVISIBLE (-925 -425);
FORCEPROP 1 LAST TOLERANCE 1%
J 0
(-900 -375);
DISPLAY 0.638298 (-900 -375);
DISPLAY INVISIBLE (-900 -375);
FORCEPROP 1 LAST PACK_TYPE 0402LF
J 0
(-800 -375);
DISPLAY 0.638298 (-800 -375);
DISPLAY INVISIBLE (-800 -375);
FORCEPROP 1 LAST PATH I24
J 0
(-950 -175);
DISPLAY 0.978723 (-950 -175);
PAINT WHITE (-950 -175);
DISPLAY INVISIBLE (-950 -175);
FORCEPROP 0 LAST CDS_LOCATION R4457
J 0
(-1050 -250);
DISPLAY 1.021277 (-1050 -250);
DISPLAY INVISIBLE (-1050 -250);
FORCEPROP 0 LAST $SEC 1
J 0
(-1050 -250);
DISPLAY 0.680851 (-1050 -250);
PAINT MONO (-1050 -250);
DISPLAY INVISIBLE (-1050 -250);
FORCEPROP 0 LAST CDS_SEC 1
J 0
(-1050 -250);
DISPLAY 1.021277 (-1050 -250);
DISPLAY INVISIBLE (-1050 -250);
FORCEADD Q_RES..1
(-900 -175);
FORCEPROP 1 LAST PART_NUMBER CS31002FB08
J 0
(-1075 -325);
DISPLAY 0.638298 (-1075 -325);
DISPLAY INVISIBLE (-1075 -325);
FORCEPROP 1 LAST VALUE 10K
J 2
(-925 -225);
DISPLAY 0.638298 (-925 -225);
FORCEPROP 1 LAST MATERIAL EMPTY
J 0
(-875 -225);
DISPLAY 0.638298 (-875 -225);
PAINT RED (-875 -225);
FORCEPROP 1 LAST $LOCATION R4456
J 0
(-1075 -175);
DISPLAY 0.638298 (-1075 -175);
FORCEPROP 1 LASTPIN (-1000 -175) $PN 1
J 0
(-988 -163);
DISPLAY 0.787234 (-988 -163);
PAINT MONO (-988 -163);
FORCEPROP 1 LASTPIN (-800 -175) $PN 2
J 0
(-838 -163);
DISPLAY 0.787234 (-838 -163);
PAINT MONO (-838 -163);
FORCEPROP 2 LAST CDS_LIB pure_quanta
J 0
(-900 -175);
DISPLAY INVISIBLE (-900 -175);
FORCEPROP 1 LAST PACK_TYPE 0402LF
J 0
(-800 -225);
DISPLAY 0.638298 (-800 -225);
DISPLAY INVISIBLE (-800 -225);
FORCEPROP 1 LAST TOLERANCE 1%
J 0
(-900 -225);
DISPLAY 0.638298 (-900 -225);
DISPLAY INVISIBLE (-900 -225);
FORCEPROP 1 LAST WATTAGE 1/16W
J 2
(-925 -275);
DISPLAY 0.638298 (-925 -275);
DISPLAY INVISIBLE (-925 -275);
FORCEPROP 1 LAST PATH I25
J 0
(-950 -25);
DISPLAY 0.978723 (-950 -25);
PAINT WHITE (-950 -25);
DISPLAY INVISIBLE (-950 -25);
FORCEPROP 0 LAST CDS_LOCATION R4456
J 0
(-1050 -100);
DISPLAY 1.021277 (-1050 -100);
DISPLAY INVISIBLE (-1050 -100);
FORCEPROP 0 LAST $SEC 1
J 0
(-1050 -100);
DISPLAY 0.680851 (-1050 -100);
PAINT MONO (-1050 -100);
DISPLAY INVISIBLE (-1050 -100);
FORCEPROP 0 LAST CDS_SEC 1
J 0
(-1050 -100);
DISPLAY 1.021277 (-1050 -100);
DISPLAY INVISIBLE (-1050 -100);
FORCEADD Q_RES..1
R 1
(-1250 650);
FORCEPROP 1 LAST PART_NUMBER CS34702BB05
J 0
(-1175 525);
DISPLAY 0.638298 (-1175 525);
DISPLAY INVISIBLE (-1175 525);
FORCEPROP 1 LAST PACK_TYPE 0402LF
J 0
(-1175 475);
DISPLAY 0.638298 (-1175 475);
FORCEPROP 1 LAST MATERIAL EMPTY
J 0
(-1175 575);
DISPLAY 0.638298 (-1175 575);
PAINT RED (-1175 575);
FORCEPROP 1 LAST VALUE 47K
J 2
(-1075 725);
DISPLAY 0.638298 (-1075 725);
FORCEPROP 1 LAST TOLERANCE 0.1%
J 0
(-1175 675);
DISPLAY 0.638298 (-1175 675);
FORCEPROP 1 LAST WATTAGE 1/16W
J 2
(-1025 625);
DISPLAY 0.638298 (-1025 625);
FORCEPROP 1 LAST $LOCATION R4453
J 0
(-1175 775);
DISPLAY 0.638298 (-1175 775);
FORCEPROP 1 LASTPIN (-1250 550) $PN 1
R 1
J 0
(-1262 562);
DISPLAY 0.787234 (-1262 562);
PAINT MONO (-1262 562);
FORCEPROP 1 LASTPIN (-1250 750) $PN 2
R 1
J 0
(-1262 712);
DISPLAY 0.787234 (-1262 712);
PAINT MONO (-1262 712);
FORCEPROP 2 LAST CDS_LIB pure_quanta
R 1
J 0
(-1250 650);
DISPLAY INVISIBLE (-1250 650);
FORCEPROP 1 LAST PATH I26
R 1
J 0
(-1400 600);
DISPLAY 0.978723 (-1400 600);
PAINT WHITE (-1400 600);
DISPLAY INVISIBLE (-1400 600);
FORCEPROP 0 LAST CDS_LOCATION R4453
R 1
J 0
(-1175 825);
DISPLAY 1.021277 (-1175 825);
DISPLAY INVISIBLE (-1175 825);
FORCEPROP 0 LAST $SEC 1
R 1
J 0
(-1175 825);
DISPLAY 0.680851 (-1175 825);
PAINT MONO (-1175 825);
DISPLAY INVISIBLE (-1175 825);
FORCEPROP 0 LAST CDS_SEC 1
R 1
J 0
(-1175 825);
DISPLAY 1.021277 (-1175 825);
DISPLAY INVISIBLE (-1175 825);
FORCEADD Q_RES..2
(-1250 1325);
FORCEPROP 1 LAST PART_NUMBER CS31002FB08
J 0
(-1210 1200);
DISPLAY 0.638298 (-1210 1200);
DISPLAY INVISIBLE (-1210 1200);
FORCEPROP 1 LAST VALUE 10K
J 0
(-1205 1400);
DISPLAY 0.638298 (-1205 1400);
FORCEPROP 1 LAST TOLERANCE 1%
J 0
(-1205 1350);
DISPLAY 0.638298 (-1205 1350);
FORCEPROP 1 LAST PACK_TYPE 0402LF
J 0
(-1210 1150);
DISPLAY 0.638298 (-1210 1150);
FORCEPROP 1 LAST WATTAGE 1/16W
J 0
(-1210 1300);
DISPLAY 0.638298 (-1210 1300);
FORCEPROP 1 LAST MATERIAL EMPTY
J 0
(-1210 1250);
DISPLAY 0.638298 (-1210 1250);
FORCEPROP 1 LAST $LOCATION R4452
J 0
(-1205 1450);
DISPLAY 0.638298 (-1205 1450);
FORCEPROP 1 LASTPIN (-1250 1425) $PN 1
J 0
(-1245 1387);
DISPLAY 0.787234 (-1245 1387);
PAINT MONO (-1245 1387);
FORCEPROP 1 LASTPIN (-1250 1225) $PN 2
J 0
(-1245 1235);
DISPLAY 0.787234 (-1245 1235);
PAINT MONO (-1245 1235);
FORCEPROP 2 LAST CDS_LIB pure_quanta
J 0
(-1250 1325);
DISPLAY INVISIBLE (-1250 1325);
FORCEPROP 1 LAST PATH I27
J 0
(-1200 1500);
DISPLAY 0.978723 (-1200 1500);
PAINT WHITE (-1200 1500);
DISPLAY INVISIBLE (-1200 1500);
FORCEPROP 0 LAST CDS_LOCATION R4452
J 0
(-1200 1500);
DISPLAY 1.021277 (-1200 1500);
DISPLAY INVISIBLE (-1200 1500);
FORCEPROP 0 LAST $SEC 1
J 0
(-1200 1500);
DISPLAY 0.680851 (-1200 1500);
PAINT MONO (-1200 1500);
DISPLAY INVISIBLE (-1200 1500);
FORCEPROP 0 LAST CDS_SEC 1
J 0
(-1200 1500);
DISPLAY 1.021277 (-1200 1500);
DISPLAY INVISIBLE (-1200 1500);
FORCEADD OFFPAGE..1
(-375 1225);
PAINT AQUA (-375 1225);
FORCEPROP 2 LAST $XR0 196 
J 0
(-627 1225);
DISPLAY 0.638298 (-627 1225);
PAINT MONO (-627 1225);
FORCEPROP 2 LAST CDS_LIB standard
J 0
(-375 1225);
DISPLAY INVISIBLE (-375 1225);
FORCEPROP 1 LAST OFFPAGE TRUE
J 0
(-50 1100);
DISPLAY 0.872340 (-50 1100);
PAINT AQUA (-50 1100);
DISPLAY INVISIBLE (-50 1100);
FORCEPROP 1 LAST COMMENT_BODY TRUE
J 0
(-250 1125);
DISPLAY 0.872340 (-250 1125);
PAINT GREEN (-250 1125);
DISPLAY INVISIBLE (-250 1125);
FORCEPROP 2 LAST PATH I28
J 0
(-650 1275);
DISPLAY 1.021277 (-650 1275);
DISPLAY INVISIBLE (-650 1275);
FORCEADD OFFPAGE..1
(-375 1175);
PAINT AQUA (-375 1175);
FORCEPROP 2 LAST $XR0 196 
J 0
(-627 1175);
DISPLAY 0.638298 (-627 1175);
PAINT MONO (-627 1175);
FORCEPROP 2 LAST CDS_LIB standard
J 0
(-375 1175);
DISPLAY INVISIBLE (-375 1175);
FORCEPROP 1 LAST OFFPAGE TRUE
J 0
(-50 1050);
DISPLAY 0.872340 (-50 1050);
PAINT AQUA (-50 1050);
DISPLAY INVISIBLE (-50 1050);
FORCEPROP 1 LAST COMMENT_BODY TRUE
J 0
(-250 1075);
DISPLAY 0.872340 (-250 1075);
PAINT GREEN (-250 1075);
DISPLAY INVISIBLE (-250 1075);
FORCEPROP 2 LAST PATH I29
J 0
(-650 1225);
DISPLAY 1.021277 (-650 1225);
DISPLAY INVISIBLE (-650 1225);
FORCEADD UNIVERSAL_GND..1
(-25 -2900);
FORCEPROP 3 LASTPIN (-25 -2850) SIG_NAME GND\g
J 0
(-15 -2840);
DISPLAY 0.659574 (-15 -2840);
PAINT MONO (-15 -2840);
DISPLAY INVISIBLE (-15 -2840);
FORCEPROP 2 LAST CDS_LIB logical_power
J 0
(-25 -2900);
DISPLAY INVISIBLE (-25 -2900);
FORCEPROP 1 LAST HDL_POWER GND
J 1
(0 -2975);
DISPLAY 0.872340 (0 -2975);
PAINT GREEN (0 -2975);
DISPLAY INVISIBLE (0 -2975);
FORCEPROP 1 LAST PATH I3
J 0
(50 -2900);
DISPLAY 0.872340 (50 -2900);
PAINT AQUA (50 -2900);
DISPLAY INVISIBLE (50 -2900);
FORCEADD OFFPAGE..1
(-375 1275);
PAINT AQUA (-375 1275);
FORCEPROP 2 LAST $XR0 196 
J 0
(-627 1275);
DISPLAY 0.638298 (-627 1275);
PAINT MONO (-627 1275);
FORCEPROP 2 LAST CDS_LIB standard
J 0
(-375 1275);
DISPLAY INVISIBLE (-375 1275);
FORCEPROP 1 LAST OFFPAGE TRUE
J 0
(-50 1150);
DISPLAY 0.872340 (-50 1150);
PAINT AQUA (-50 1150);
DISPLAY INVISIBLE (-50 1150);
FORCEPROP 1 LAST COMMENT_BODY TRUE
J 0
(-250 1175);
DISPLAY 0.872340 (-250 1175);
PAINT GREEN (-250 1175);
DISPLAY INVISIBLE (-250 1175);
FORCEPROP 2 LAST PATH I30
J 0
(-650 1325);
DISPLAY 1.021277 (-650 1325);
DISPLAY INVISIBLE (-650 1325);
FORCEADD OFFPAGE..1
(-375 1325);
PAINT AQUA (-375 1325);
FORCEPROP 2 LAST $XR0 196 
J 0
(-627 1325);
DISPLAY 0.638298 (-627 1325);
PAINT MONO (-627 1325);
FORCEPROP 2 LAST CDS_LIB standard
J 0
(-375 1325);
DISPLAY INVISIBLE (-375 1325);
FORCEPROP 1 LAST OFFPAGE TRUE
J 0
(-50 1200);
DISPLAY 0.872340 (-50 1200);
PAINT AQUA (-50 1200);
DISPLAY INVISIBLE (-50 1200);
FORCEPROP 1 LAST COMMENT_BODY TRUE
J 0
(-250 1225);
DISPLAY 0.872340 (-250 1225);
PAINT GREEN (-250 1225);
DISPLAY INVISIBLE (-250 1225);
FORCEPROP 2 LAST PATH I31
J 0
(-650 1375);
DISPLAY 1.021277 (-650 1375);
DISPLAY INVISIBLE (-650 1375);
FORCEADD OFFPAGE..5
R 2
(-175 -575);
FORCEPROP 2 LAST $XR0 196 
J 0
(14 -575);
DISPLAY 0.638298 (14 -575);
PAINT MONO (14 -575);
FORCEPROP 2 LAST CDS_LIB standard
J 0
(-175 -575);
DISPLAY INVISIBLE (-175 -575);
FORCEPROP 1 LAST OFFPAGE TRUE
J 2
(-500 -700);
DISPLAY 0.872340 (-500 -700);
PAINT GREEN (-500 -700);
DISPLAY INVISIBLE (-500 -700);
FORCEPROP 1 LAST COMMENT_BODY TRUE
J 2
(-275 -650);
DISPLAY 0.872340 (-275 -650);
PAINT GREEN (-275 -650);
DISPLAY INVISIBLE (-275 -650);
FORCEPROP 2 LAST PATH I32
J 0
(25 -525);
DISPLAY 1.021277 (25 -525);
DISPLAY INVISIBLE (25 -525);
FORCEADD OFFPAGE..5
R 2
(-175 -450);
FORCEPROP 2 LAST $XR0 196 
J 0
(14 -450);
DISPLAY 0.638298 (14 -450);
PAINT MONO (14 -450);
FORCEPROP 2 LAST CDS_LIB standard
J 0
(-175 -450);
DISPLAY INVISIBLE (-175 -450);
FORCEPROP 1 LAST OFFPAGE TRUE
J 2
(-500 -575);
DISPLAY 0.872340 (-500 -575);
PAINT GREEN (-500 -575);
DISPLAY INVISIBLE (-500 -575);
FORCEPROP 1 LAST COMMENT_BODY TRUE
J 2
(-275 -525);
DISPLAY 0.872340 (-275 -525);
PAINT GREEN (-275 -525);
DISPLAY INVISIBLE (-275 -525);
FORCEPROP 2 LAST PATH I33
J 0
(25 -400);
DISPLAY 1.021277 (25 -400);
DISPLAY INVISIBLE (25 -400);
FORCEADD OFFPAGE..5
R 2
(-175 -175);
FORCEPROP 2 LAST $XR0 196 
J 0
(14 -175);
DISPLAY 0.638298 (14 -175);
PAINT MONO (14 -175);
FORCEPROP 2 LAST CDS_LIB standard
J 2
(-175 -175);
DISPLAY INVISIBLE (-175 -175);
FORCEPROP 1 LAST OFFPAGE TRUE
J 2
(-500 -300);
DISPLAY 0.872340 (-500 -300);
PAINT GREEN (-500 -300);
DISPLAY INVISIBLE (-500 -300);
FORCEPROP 1 LAST COMMENT_BODY TRUE
J 2
(-275 -250);
DISPLAY 0.872340 (-275 -250);
PAINT GREEN (-275 -250);
DISPLAY INVISIBLE (-275 -250);
FORCEPROP 2 LAST PATH I34
J 0
(25 -125);
DISPLAY 1.021277 (25 -125);
DISPLAY INVISIBLE (25 -125);
FORCEADD UNIVERSAL_GND..1
(-100 350);
FORCEPROP 3 LASTPIN (-100 400) SIG_NAME GND\g
J 0
(-90 410);
DISPLAY 0.659574 (-90 410);
PAINT MONO (-90 410);
DISPLAY INVISIBLE (-90 410);
FORCEPROP 2 LAST CDS_LIB logical_power
J 0
(-100 350);
DISPLAY INVISIBLE (-100 350);
FORCEPROP 1 LAST HDL_POWER GND
J 1
(-75 275);
DISPLAY 0.872340 (-75 275);
PAINT GREEN (-75 275);
DISPLAY INVISIBLE (-75 275);
FORCEPROP 1 LAST PATH I35
J 0
(-25 350);
DISPLAY 0.872340 (-25 350);
PAINT AQUA (-25 350);
DISPLAY INVISIBLE (-25 350);
FORCEADD UNIVERSAL_GND..1
(-425 375);
FORCEPROP 3 LASTPIN (-425 425) SIG_NAME GND\g
J 0
(-415 435);
DISPLAY 0.659574 (-415 435);
PAINT MONO (-415 435);
DISPLAY INVISIBLE (-415 435);
FORCEPROP 2 LAST CDS_LIB logical_power
J 0
(-425 375);
DISPLAY INVISIBLE (-425 375);
FORCEPROP 1 LAST HDL_POWER GND
J 1
(-400 300);
DISPLAY 0.872340 (-400 300);
PAINT GREEN (-400 300);
DISPLAY INVISIBLE (-400 300);
FORCEPROP 1 LAST PATH I36
J 0
(-350 375);
DISPLAY 0.872340 (-350 375);
PAINT AQUA (-350 375);
DISPLAY INVISIBLE (-350 375);
FORCEADD Q_RES..2
(-425 650);
FORCEPROP 1 LAST PART_NUMBER CS16802FB03
J 0
(-385 525);
DISPLAY 0.510638 (-385 525);
DISPLAY INVISIBLE (-385 525);
FORCEPROP 1 LAST PACK_TYPE 0402LF
J 0
(-385 475);
DISPLAY 0.510638 (-385 475);
FORCEPROP 1 LAST MATERIAL EMPTY
J 0
(-385 575);
DISPLAY 0.510638 (-385 575);
FORCEPROP 1 LAST WATTAGE 1/16W
J 0
(-385 625);
DISPLAY 0.510638 (-385 625);
FORCEPROP 1 LAST TOLERANCE 1%
J 0
(-380 675);
DISPLAY 0.510638 (-380 675);
FORCEPROP 1 LAST VALUE 680
J 0
(-380 725);
DISPLAY 0.404255 (-380 725);
FORCEPROP 1 LAST $LOCATION R4463
J 0
(-380 775);
DISPLAY 0.510638 (-380 775);
FORCEPROP 1 LASTPIN (-425 750) $PN 1
J 0
(-420 712);
DISPLAY 0.787234 (-420 712);
PAINT MONO (-420 712);
FORCEPROP 1 LASTPIN (-425 550) $PN 2
J 0
(-420 560);
DISPLAY 0.787234 (-420 560);
PAINT MONO (-420 560);
FORCEPROP 2 LAST CDS_LIB pure_quanta
J 0
(-425 650);
DISPLAY INVISIBLE (-425 650);
FORCEPROP 1 LAST PATH I37
J 0
(-375 825);
DISPLAY 0.978723 (-375 825);
PAINT WHITE (-375 825);
DISPLAY INVISIBLE (-375 825);
FORCEPROP 0 LAST CDS_LOCATION R4463
J 0
(-375 825);
DISPLAY 1.021277 (-375 825);
DISPLAY INVISIBLE (-375 825);
FORCEPROP 0 LAST $SEC 1
J 0
(-375 825);
DISPLAY 0.680851 (-375 825);
PAINT MONO (-375 825);
DISPLAY INVISIBLE (-375 825);
FORCEPROP 0 LAST CDS_SEC 1
J 0
(-375 825);
DISPLAY 1.021277 (-375 825);
DISPLAY INVISIBLE (-375 825);
FORCEADD Q_RES..2
(-100 625);
FORCEPROP 1 LAST PART_NUMBER CS41002FB09
J 0
(-60 500);
DISPLAY 0.468085 (-60 500);
DISPLAY INVISIBLE (-60 500);
FORCEPROP 1 LAST PACK_TYPE 0402LF
J 0
(-60 450);
DISPLAY 0.468085 (-60 450);
FORCEPROP 1 LAST TOLERANCE 1%
J 0
(-55 650);
DISPLAY 0.468085 (-55 650);
FORCEPROP 1 LAST VALUE 100K
J 0
(-55 700);
DISPLAY 0.468085 (-55 700);
FORCEPROP 1 LAST MATERIAL EMPTY
J 0
(-60 550);
DISPLAY 0.468085 (-60 550);
FORCEPROP 1 LAST WATTAGE 1/16W
J 0
(-60 600);
DISPLAY 0.468085 (-60 600);
FORCEPROP 1 LAST $LOCATION R4464
J 0
(-55 750);
DISPLAY 0.510638 (-55 750);
FORCEPROP 1 LASTPIN (-100 725) $PN 1
J 0
(-95 687);
DISPLAY 0.787234 (-95 687);
PAINT MONO (-95 687);
FORCEPROP 1 LASTPIN (-100 525) $PN 2
J 0
(-95 535);
DISPLAY 0.787234 (-95 535);
PAINT MONO (-95 535);
FORCEPROP 2 LAST CDS_LIB pure_quanta
J 0
(-100 625);
DISPLAY INVISIBLE (-100 625);
FORCEPROP 1 LAST PATH I38
J 0
(-50 800);
DISPLAY 0.978723 (-50 800);
PAINT WHITE (-50 800);
DISPLAY INVISIBLE (-50 800);
FORCEPROP 0 LAST CDS_LOCATION R4464
J 0
(-50 800);
DISPLAY 1.021277 (-50 800);
DISPLAY INVISIBLE (-50 800);
FORCEPROP 0 LAST $SEC 1
J 0
(-50 800);
DISPLAY 0.680851 (-50 800);
PAINT MONO (-50 800);
DISPLAY INVISIBLE (-50 800);
FORCEPROP 0 LAST CDS_SEC 1
J 0
(-50 800);
DISPLAY 1.021277 (-50 800);
DISPLAY INVISIBLE (-50 800);
FORCEADD OFFPAGE..1
(-225 925);
PAINT AQUA (-225 925);
FORCEPROP 2 LAST $XR0 196 
J 0
(-537 925);
DISPLAY 0.638298 (-537 925);
PAINT MONO (-537 925);
FORCEPROP 2 LAST CDS_LIB standard
J 0
(-225 925);
DISPLAY INVISIBLE (-225 925);
FORCEPROP 1 LAST OFFPAGE TRUE
J 0
(100 800);
DISPLAY 0.872340 (100 800);
PAINT AQUA (100 800);
DISPLAY INVISIBLE (100 800);
FORCEPROP 1 LAST COMMENT_BODY TRUE
J 0
(-100 825);
DISPLAY 0.872340 (-100 825);
PAINT GREEN (-100 825);
DISPLAY INVISIBLE (-100 825);
FORCEPROP 2 LAST PATH I39
J 0
(-525 975);
DISPLAY 1.021277 (-525 975);
DISPLAY INVISIBLE (-525 975);
FORCEADD Q_RES..2
(-25 -2700);
FORCEPROP 1 LAST PART_NUMBER CS23902JB04
J 0
(15 -2825);
DISPLAY 0.723404 (15 -2825);
PAINT WHITE (15 -2825);
DISPLAY INVISIBLE (15 -2825);
FORCEPROP 1 LAST PACK_TYPE 0402LF
J 0
(15 -2875);
DISPLAY 0.723404 (15 -2875);
PAINT SKYBLUE (15 -2875);
FORCEPROP 1 LAST MATERIAL EMPTY
J 0
(15 -2775);
DISPLAY 0.723404 (15 -2775);
PAINT SKYBLUE (15 -2775);
FORCEPROP 1 LAST TOLERANCE 5%
J 0
(20 -2675);
DISPLAY 0.723404 (20 -2675);
PAINT SKYBLUE (20 -2675);
FORCEPROP 1 LAST WATTAGE 1/16W
J 0
(15 -2725);
DISPLAY 0.723404 (15 -2725);
PAINT SKYBLUE (15 -2725);
FORCEPROP 1 LAST VALUE 3.9K
J 0
(20 -2625);
DISPLAY 0.723404 (20 -2625);
PAINT SKYBLUE (20 -2625);
FORCEPROP 1 LAST $LOCATION R4465
J 0
(20 -2575);
DISPLAY 0.723404 (20 -2575);
PAINT AQUA (20 -2575);
FORCEPROP 2 LAST CDS_LIB pure_quanta
J 0
(-25 -2700);
DISPLAY INVISIBLE (-25 -2700);
FORCEPROP 1 LAST PATH I4
J 0
(25 -2525);
DISPLAY 0.978723 (25 -2525);
PAINT WHITE (25 -2525);
DISPLAY INVISIBLE (25 -2525);
FORCEPROP 0 LAST CDS_LOCATION R4465
J 0
(25 -2525);
DISPLAY INVISIBLE (25 -2525);
FORCEPROP 0 LAST $SEC 1
J 0
(25 -2525);
DISPLAY INVISIBLE (25 -2525);
FORCEPROP 0 LAST CDS_SEC 1
J 0
(25 -2525);
DISPLAY INVISIBLE (25 -2525);
FORCEPROP 1 LASTPIN (-25 -2600) $PN 1
J 0
(-20 -2638);
DISPLAY 0.787234 (-20 -2638);
PAINT MONO (-20 -2638);
DISPLAY INVISIBLE (-20 -2638);
FORCEPROP 1 LASTPIN (-25 -2800) $PN 2
J 0
(-20 -2790);
DISPLAY 0.787234 (-20 -2790);
PAINT MONO (-20 -2790);
DISPLAY INVISIBLE (-20 -2790);
FORCEADD GL852GOHY60..1
(775 1375);
FORCEPROP 1 LAST PART_NUMBER AL000852001
J 0
(455 2122);
DISPLAY 0.723404 (455 2122);
PAINT GREEN (455 2122);
DISPLAY INVISIBLE (455 2122);
FORCEPROP 2 LAST VALUE GL852G-OHY60
J 0
(475 2325);
DISPLAY 1.021277 (475 2325);
FORCEPROP 1 LAST MATERIAL EMPTY
J 0
(455 1995);
DISPLAY 0.723404 (455 1995);
PAINT GREEN (455 1995);
FORCEPROP 2 LAST PART_TYPE SMLF
J 0
(475 2375);
DISPLAY 1.021277 (475 2375);
FORCEPROP 1 LAST $LOCATION U313
J 0
(455 2269);
DISPLAY 0.723404 (455 2269);
PAINT GREEN (455 2269);
FORCEPROP 0 LASTPIN (300 1675) $PN 5
J 2
(290 1685);
DISPLAY 0.680851 (290 1685);
PAINT MONO (290 1685);
FORCEPROP 0 LASTPIN (300 1625) $PN 9
J 2
(290 1635);
DISPLAY 0.680851 (290 1635);
PAINT MONO (290 1635);
FORCEPROP 0 LASTPIN (300 1575) $PN 14
J 2
(290 1585);
DISPLAY 0.680851 (290 1585);
PAINT MONO (290 1585);
FORCEPROP 0 LASTPIN (1250 1425) $PN 1
J 0
(1260 1435);
DISPLAY 0.680851 (1260 1435);
PAINT MONO (1260 1435);
FORCEPROP 0 LASTPIN (1250 1325) $PN 3
J 0
(1260 1335);
DISPLAY 0.680851 (1260 1335);
PAINT MONO (1260 1335);
FORCEPROP 0 LASTPIN (1250 1225) $PN 6
J 0
(1260 1235);
DISPLAY 0.680851 (1260 1235);
PAINT MONO (1260 1235);
FORCEPROP 0 LASTPIN (1250 1125) $PN 12
J 0
(1260 1135);
DISPLAY 0.680851 (1260 1135);
PAINT MONO (1260 1135);
FORCEPROP 0 LASTPIN (1250 1025) $PN 15
J 0
(1260 1035);
DISPLAY 0.680851 (1260 1035);
PAINT MONO (1260 1035);
FORCEPROP 0 LASTPIN (1250 1475) $PN 2
J 0
(1260 1485);
DISPLAY 0.680851 (1260 1485);
PAINT MONO (1260 1485);
FORCEPROP 0 LASTPIN (1250 1375) $PN 4
J 0
(1260 1385);
DISPLAY 0.680851 (1260 1385);
PAINT MONO (1260 1385);
FORCEPROP 0 LASTPIN (1250 1275) $PN 7
J 0
(1260 1285);
DISPLAY 0.680851 (1260 1285);
PAINT MONO (1260 1285);
FORCEPROP 0 LASTPIN (1250 1175) $PN 13
J 0
(1260 1185);
DISPLAY 0.680851 (1260 1185);
PAINT MONO (1260 1185);
FORCEPROP 0 LASTPIN (1250 1075) $PN 16
J 0
(1260 1085);
DISPLAY 0.680851 (1260 1085);
PAINT MONO (1260 1085);
FORCEPROP 0 LASTPIN (300 1475) $PN 21
J 2
(290 1485);
DISPLAY 0.680851 (290 1485);
PAINT MONO (290 1485);
FORCEPROP 0 LASTPIN (300 1325) $PN 25
J 2
(290 1335);
DISPLAY 0.680851 (290 1335);
PAINT MONO (290 1335);
FORCEPROP 0 LASTPIN (300 1275) $PN 24
J 2
(290 1285);
DISPLAY 0.680851 (290 1285);
PAINT MONO (290 1285);
FORCEPROP 0 LASTPIN (300 1225) $PN 20
J 2
(290 1235);
DISPLAY 0.680851 (290 1235);
PAINT MONO (290 1235);
FORCEPROP 0 LASTPIN (300 1175) $PN 19
J 2
(290 1185);
DISPLAY 0.680851 (290 1185);
PAINT MONO (290 1185);
FORCEPROP 0 LASTPIN (300 875) $PN 23
J 2
(290 885);
DISPLAY 0.680851 (290 885);
PAINT MONO (290 885);
FORCEPROP 0 LASTPIN (300 925) $PN 22
J 2
(290 935);
DISPLAY 0.680851 (290 935);
PAINT MONO (290 935);
FORCEPROP 0 LASTPIN (300 975) $PN 17
J 2
(290 985);
DISPLAY 0.680851 (290 985);
PAINT MONO (290 985);
FORCEPROP 0 LASTPIN (300 1025) $PN 8
J 2
(290 1035);
DISPLAY 0.680851 (290 1035);
PAINT MONO (290 1035);
FORCEPROP 0 LASTPIN (1250 1875) $PN 26
J 0
(1260 1885);
DISPLAY 0.680851 (1260 1885);
PAINT MONO (1260 1885);
FORCEPROP 0 LASTPIN (1250 1825) $PN 18
J 0
(1260 1835);
DISPLAY 0.680851 (1260 1835);
PAINT MONO (1260 1835);
FORCEPROP 0 LASTPIN (1250 875) $PN TH
J 0
(1260 885);
DISPLAY 0.680851 (1260 885);
PAINT MONO (1260 885);
FORCEPROP 0 LASTPIN (300 1875) $PN 27
J 2
(290 1885);
DISPLAY 0.680851 (290 1885);
PAINT MONO (290 1885);
FORCEPROP 0 LASTPIN (300 1775) $PN 28
J 2
(290 1785);
DISPLAY 0.680851 (290 1785);
PAINT MONO (290 1785);
FORCEPROP 0 LASTPIN (1250 1675) $PN 10
J 0
(1265 1685);
DISPLAY 0.680851 (1265 1685);
PAINT MONO (1265 1685);
FORCEPROP 0 LASTPIN (1250 1625) $PN 11
J 0
(1260 1635);
DISPLAY 0.680851 (1260 1635);
PAINT MONO (1260 1635);
FORCEPROP 1 LAST NEEDS_NO_SIZE TRUE
J 0
(775 1375);
DISPLAY 0.723404 (775 1375);
PAINT GREEN (775 1375);
DISPLAY INVISIBLE (775 1375);
FORCEPROP 1 LAST CDS_LMAN_SYM_OUTLINE -325,600,325,-600
J 0
(775 1375);
DISPLAY 0.468085 (775 1375);
PAINT GREEN (775 1375);
DISPLAY INVISIBLE (775 1375);
FORCEPROP 2 LAST CDS_LIB pure_quanta
J 0
(775 1375);
DISPLAY INVISIBLE (775 1375);
FORCEPROP 1 LAST PATH I40
J 0
(775 1375);
DISPLAY 0.723404 (775 1375);
PAINT GREEN (775 1375);
DISPLAY INVISIBLE (775 1375);
FORCEPROP 0 LAST CDS_LOCATION U313
J 0
(475 2425);
DISPLAY 1.021277 (475 2425);
DISPLAY INVISIBLE (475 2425);
FORCEPROP 0 LAST $SEC 1
J 0
(475 2425);
DISPLAY 0.680851 (475 2425);
PAINT MONO (475 2425);
DISPLAY INVISIBLE (475 2425);
FORCEPROP 0 LAST CDS_SEC 1
J 0
(475 2425);
DISPLAY 1.021277 (475 2425);
DISPLAY INVISIBLE (475 2425);
FORCEADD Q_RES..1
(-3100 2350);
FORCEPROP 1 LAST PART_NUMBER CS00002JB13
J 0
(-3375 2225);
DISPLAY 0.723404 (-3375 2225);
PAINT WHITE (-3375 2225);
DISPLAY INVISIBLE (-3375 2225);
FORCEPROP 1 LAST VALUE 0
J 2
(-2950 2350);
DISPLAY 0.723404 (-2950 2350);
FORCEPROP 1 LAST PACK_TYPE 0402LF
J 0
(-3100 2275);
DISPLAY 0.723404 (-3100 2275);
FORCEPROP 1 LAST MATERIAL EMPTY
J 0
(-3300 2275);
DISPLAY 0.723404 (-3300 2275);
FORCEPROP 1 LAST $LOCATION R4450
J 0
(-3325 2350);
DISPLAY 0.638298 (-3325 2350);
FORCEPROP 1 LASTPIN (-3200 2350) $PN 1
J 0
(-3188 2362);
DISPLAY 0.787234 (-3188 2362);
PAINT MONO (-3188 2362);
FORCEPROP 1 LASTPIN (-3000 2350) $PN 2
J 0
(-3038 2362);
DISPLAY 0.787234 (-3038 2362);
PAINT MONO (-3038 2362);
FORCEPROP 2 LAST CDS_LIB pure_quanta
J 0
(-3100 2350);
DISPLAY INVISIBLE (-3100 2350);
FORCEPROP 1 LAST WATTAGE 1/16W
J 2
(-3025 2275);
DISPLAY 0.723404 (-3025 2275);
PAINT SKYBLUE (-3025 2275);
DISPLAY INVISIBLE (-3025 2275);
FORCEPROP 1 LAST TOLERANCE 5%
J 0
(-3300 2275);
DISPLAY 0.723404 (-3300 2275);
PAINT SKYBLUE (-3300 2275);
DISPLAY INVISIBLE (-3300 2275);
FORCEPROP 1 LAST PATH I41
J 0
(-3150 2500);
DISPLAY 0.978723 (-3150 2500);
PAINT WHITE (-3150 2500);
DISPLAY INVISIBLE (-3150 2500);
FORCEPROP 0 LAST CDS_LOCATION R4450
J 0
(-2950 2400);
DISPLAY 1.021277 (-2950 2400);
DISPLAY INVISIBLE (-2950 2400);
FORCEPROP 0 LAST $SEC 1
J 0
(-2950 2400);
DISPLAY 0.680851 (-2950 2400);
PAINT MONO (-2950 2400);
DISPLAY INVISIBLE (-2950 2400);
FORCEPROP 0 LAST CDS_SEC 1
J 0
(-2950 2400);
DISPLAY 1.021277 (-2950 2400);
DISPLAY INVISIBLE (-2950 2400);
FORCEADD UNIVERSAL_GND..1
(-2800 1650);
FORCEPROP 3 LASTPIN (-2800 1700) SIG_NAME GND\g
J 0
(-2790 1710);
DISPLAY 0.659574 (-2790 1710);
PAINT MONO (-2790 1710);
DISPLAY INVISIBLE (-2790 1710);
FORCEPROP 2 LAST CDS_LIB logical_power
J 0
(-2800 1650);
DISPLAY INVISIBLE (-2800 1650);
FORCEPROP 1 LAST HDL_POWER GND
J 1
(-2775 1575);
DISPLAY 0.872340 (-2775 1575);
PAINT GREEN (-2775 1575);
DISPLAY INVISIBLE (-2775 1575);
FORCEPROP 1 LAST PATH I42
J 0
(-2725 1650);
DISPLAY 0.872340 (-2725 1650);
PAINT AQUA (-2725 1650);
DISPLAY INVISIBLE (-2725 1650);
FORCEADD Q_CAP..1
(-2800 2050);
FORCEPROP 1 LAST PART_NUMBER CH6101MEB01
J 0
(-2750 1900);
DISPLAY 0.510638 (-2750 1900);
DISPLAY INVISIBLE (-2750 1900);
FORCEPROP 1 LAST VOLTAGE 6.3V
J 0
(-2750 2050);
DISPLAY 0.510638 (-2750 2050);
FORCEPROP 1 LAST VALUE 10UF
J 0
(-2750 2100);
DISPLAY 0.510638 (-2750 2100);
FORCEPROP 1 LAST MATERIAL EMPTY
J 0
(-2750 1950);
DISPLAY 0.510638 (-2750 1950);
FORCEPROP 1 LAST TOLERANCE 20%
J 0
(-2750 2000);
DISPLAY 0.510638 (-2750 2000);
FORCEPROP 1 LAST PACK_TYPE C0402
J 0
(-2750 1850);
DISPLAY 0.510638 (-2750 1850);
FORCEPROP 1 LAST $LOCATION C2313
J 0
(-2750 2150);
DISPLAY 0.510638 (-2750 2150);
FORCEPROP 1 LASTPIN (-2800 2150) $PN 1
J 0
(-2790 2130);
DISPLAY 0.787234 (-2790 2130);
PAINT MONO (-2790 2130);
FORCEPROP 1 LASTPIN (-2800 1950) $PN 2
J 0
(-2790 1930);
DISPLAY 0.787234 (-2790 1930);
PAINT MONO (-2790 1930);
FORCEPROP 2 LAST CDS_LIB pure_quanta
J 0
(-2800 2050);
DISPLAY INVISIBLE (-2800 2050);
FORCEPROP 1 LAST PATH I43
J 0
(-2750 2200);
DISPLAY 0.978723 (-2750 2200);
PAINT WHITE (-2750 2200);
DISPLAY INVISIBLE (-2750 2200);
FORCEPROP 0 LAST CDS_LOCATION C2313
J 0
(-2750 2175);
DISPLAY 1.021277 (-2750 2175);
DISPLAY INVISIBLE (-2750 2175);
FORCEPROP 0 LAST $SEC 1
J 0
(-2750 2175);
DISPLAY 0.680851 (-2750 2175);
PAINT MONO (-2750 2175);
DISPLAY INVISIBLE (-2750 2175);
FORCEPROP 0 LAST CDS_SEC 1
J 0
(-2750 2175);
DISPLAY 1.021277 (-2750 2175);
DISPLAY INVISIBLE (-2750 2175);
FORCEADD UNIVERSAL_POWER..1
R 2
(-3350 2500);
FORCEPROP 3 LASTPIN (-3350 2450) SIG_NAME P3V3_AUX\g
J 0
(-3340 2460);
DISPLAY 0.659574 (-3340 2460);
PAINT MONO (-3340 2460);
DISPLAY INVISIBLE (-3340 2460);
FORCEPROP 1 LAST HDL_POWER P3V3_AUX
J 1
(-3350 2550);
DISPLAY 0.723404 (-3350 2550);
PAINT GREEN (-3350 2550);
FORCEPROP 2 LAST CDS_LIB logical_power
J 0
(-3350 2500);
DISPLAY INVISIBLE (-3350 2500);
FORCEPROP 1 LAST PATH I44
J 2
(-3400 2525);
DISPLAY 0.872340 (-3400 2525);
PAINT AQUA (-3400 2525);
DISPLAY INVISIBLE (-3400 2525);
FORCEADD Q_CAP..1
R 2
(-2425 2050);
FORCEPROP 1 LAST PART_NUMBER CH4104K1B00
J 0
(-2350 1900);
DISPLAY 0.510638 (-2350 1900);
DISPLAY INVISIBLE (-2350 1900);
FORCEPROP 1 LAST TOLERANCE 10%
J 0
(-2350 2000);
DISPLAY 0.510638 (-2350 2000);
FORCEPROP 1 LAST VOLTAGE 25V
J 0
(-2350 2050);
DISPLAY 0.510638 (-2350 2050);
FORCEPROP 1 LAST VALUE 0.1UF
J 0
(-2350 2100);
DISPLAY 0.510638 (-2350 2100);
FORCEPROP 1 LAST MATERIAL EMPTY
J 0
(-2350 1950);
DISPLAY 0.510638 (-2350 1950);
FORCEPROP 1 LAST PACK_TYPE 0402
J 0
(-2350 1850);
DISPLAY 0.510638 (-2350 1850);
FORCEPROP 1 LAST $LOCATION C2314
J 0
(-2350 2175);
DISPLAY 0.638298 (-2350 2175);
FORCEPROP 1 LASTPIN (-2425 2150) $PN 1
J 2
(-2435 2130);
DISPLAY 0.787234 (-2435 2130);
PAINT MONO (-2435 2130);
FORCEPROP 1 LASTPIN (-2425 1950) $PN 2
J 2
(-2435 1930);
DISPLAY 0.787234 (-2435 1930);
PAINT MONO (-2435 1930);
FORCEPROP 2 LAST CDS_LIB pure_quanta
J 0
(-2425 2050);
DISPLAY INVISIBLE (-2425 2050);
FORCEPROP 1 LAST PATH I45
J 2
(-2475 2200);
DISPLAY 0.978723 (-2475 2200);
PAINT WHITE (-2475 2200);
DISPLAY INVISIBLE (-2475 2200);
FORCEPROP 0 LAST CDS_LOCATION C2314
J 0
(-2325 2175);
DISPLAY 1.021277 (-2325 2175);
DISPLAY INVISIBLE (-2325 2175);
FORCEPROP 0 LAST $SEC 1
J 0
(-2325 2175);
DISPLAY 0.680851 (-2325 2175);
PAINT MONO (-2325 2175);
DISPLAY INVISIBLE (-2325 2175);
FORCEPROP 0 LAST CDS_SEC 1
J 0
(-2325 2175);
DISPLAY 1.021277 (-2325 2175);
DISPLAY INVISIBLE (-2325 2175);
FORCEADD Q_CAP..1
R 2
(-2025 2050);
FORCEPROP 1 LAST PART_NUMBER CH4104K1B00
J 0
(-1950 1875);
DISPLAY 0.510638 (-1950 1875);
DISPLAY INVISIBLE (-1950 1875);
FORCEPROP 1 LAST VOLTAGE 25V
J 0
(-1950 2025);
DISPLAY 0.510638 (-1950 2025);
FORCEPROP 1 LAST VALUE 0.1UF
J 0
(-1950 2075);
DISPLAY 0.510638 (-1950 2075);
FORCEPROP 1 LAST TOLERANCE 10%
J 0
(-1950 1975);
DISPLAY 0.510638 (-1950 1975);
FORCEPROP 1 LAST PACK_TYPE 0402
J 0
(-1950 1825);
DISPLAY 0.510638 (-1950 1825);
FORCEPROP 1 LAST MATERIAL EMPTY
J 0
(-1950 1925);
DISPLAY 0.510638 (-1950 1925);
FORCEPROP 1 LAST $LOCATION C2315
J 0
(-1950 2125);
DISPLAY 0.638298 (-1950 2125);
FORCEPROP 1 LASTPIN (-2025 2150) $PN 1
J 2
(-2035 2130);
DISPLAY 0.787234 (-2035 2130);
PAINT MONO (-2035 2130);
FORCEPROP 1 LASTPIN (-2025 1950) $PN 2
J 2
(-2035 1930);
DISPLAY 0.787234 (-2035 1930);
PAINT MONO (-2035 1930);
FORCEPROP 2 LAST CDS_LIB pure_quanta
J 0
(-2025 2050);
DISPLAY INVISIBLE (-2025 2050);
FORCEPROP 1 LAST PATH I46
J 2
(-2075 2200);
DISPLAY 0.978723 (-2075 2200);
PAINT WHITE (-2075 2200);
DISPLAY INVISIBLE (-2075 2200);
FORCEPROP 0 LAST CDS_LOCATION C2315
J 0
(-1925 2175);
DISPLAY 1.021277 (-1925 2175);
DISPLAY INVISIBLE (-1925 2175);
FORCEPROP 0 LAST $SEC 1
J 0
(-1925 2175);
DISPLAY 0.680851 (-1925 2175);
PAINT MONO (-1925 2175);
DISPLAY INVISIBLE (-1925 2175);
FORCEPROP 0 LAST CDS_SEC 1
J 0
(-1925 2175);
DISPLAY 1.021277 (-1925 2175);
DISPLAY INVISIBLE (-1925 2175);
FORCEADD Q_CAP..1
(-1650 2050);
FORCEPROP 1 LAST PART_NUMBER CH5104KEB02
J 0
(-1600 1900);
DISPLAY 0.574468 (-1600 1900);
DISPLAY INVISIBLE (-1600 1900);
FORCEPROP 1 LAST VOLTAGE 25V
J 0
(-1600 2050);
DISPLAY 0.574468 (-1600 2050);
FORCEPROP 1 LAST VALUE 1UF
J 0
(-1600 2100);
DISPLAY 0.574468 (-1600 2100);
FORCEPROP 1 LAST TOLERANCE 10%
J 0
(-1600 2000);
DISPLAY 0.574468 (-1600 2000);
FORCEPROP 1 LAST MATERIAL EMPTY
J 0
(-1600 1950);
DISPLAY 0.574468 (-1600 1950);
FORCEPROP 1 LAST PACK_TYPE C0402
J 0
(-1600 1850);
DISPLAY 0.574468 (-1600 1850);
FORCEPROP 1 LAST $LOCATION C2316
J 0
(-1600 2150);
DISPLAY 0.510638 (-1600 2150);
FORCEPROP 1 LASTPIN (-1650 2150) $PN 1
J 0
(-1640 2130);
DISPLAY 0.787234 (-1640 2130);
PAINT MONO (-1640 2130);
FORCEPROP 1 LASTPIN (-1650 1950) $PN 2
J 0
(-1640 1930);
DISPLAY 0.787234 (-1640 1930);
PAINT MONO (-1640 1930);
FORCEPROP 2 LAST CDS_LIB pure_quanta
J 0
(-1650 2050);
DISPLAY INVISIBLE (-1650 2050);
FORCEPROP 1 LAST PATH I47
J 0
(-1600 2200);
DISPLAY 0.978723 (-1600 2200);
PAINT WHITE (-1600 2200);
DISPLAY INVISIBLE (-1600 2200);
FORCEPROP 0 LAST CDS_LOCATION C2316
J 0
(-1600 2200);
DISPLAY 1.021277 (-1600 2200);
DISPLAY INVISIBLE (-1600 2200);
FORCEPROP 0 LAST $SEC 1
J 0
(-1600 2200);
DISPLAY 0.680851 (-1600 2200);
PAINT MONO (-1600 2200);
DISPLAY INVISIBLE (-1600 2200);
FORCEPROP 0 LAST CDS_SEC 1
J 0
(-1600 2200);
DISPLAY 1.021277 (-1600 2200);
DISPLAY INVISIBLE (-1600 2200);
FORCEADD UNIVERSAL_POWER..1
R 2
(-1250 1625);
FORCEPROP 3 LASTPIN (-1250 1575) SIG_NAME P3V3_AUX\g
J 0
(-1240 1585);
DISPLAY 0.659574 (-1240 1585);
PAINT MONO (-1240 1585);
DISPLAY INVISIBLE (-1240 1585);
FORCEPROP 1 LAST HDL_POWER P3V3_AUX
J 1
(-1250 1675);
DISPLAY 0.723404 (-1250 1675);
PAINT GREEN (-1250 1675);
FORCEPROP 2 LAST CDS_LIB logical_power
J 0
(-1250 1625);
DISPLAY INVISIBLE (-1250 1625);
FORCEPROP 1 LAST PATH I48
J 2
(-1300 1650);
DISPLAY 0.872340 (-1300 1650);
PAINT AQUA (-1300 1650);
DISPLAY INVISIBLE (-1300 1650);
FORCEADD Q_CAP..1
R 2
(-1275 2050);
FORCEPROP 1 LAST PART_NUMBER CH4104K1B00
J 0
(-1200 1900);
DISPLAY 0.510638 (-1200 1900);
DISPLAY INVISIBLE (-1200 1900);
FORCEPROP 1 LAST VOLTAGE 25V
J 0
(-1200 2050);
DISPLAY 0.510638 (-1200 2050);
FORCEPROP 1 LAST VALUE 0.1UF
J 0
(-1200 2100);
DISPLAY 0.510638 (-1200 2100);
FORCEPROP 1 LAST TOLERANCE 10%
J 0
(-1200 2000);
DISPLAY 0.510638 (-1200 2000);
FORCEPROP 1 LAST MATERIAL EMPTY
J 0
(-1200 1950);
DISPLAY 0.510638 (-1200 1950);
FORCEPROP 1 LAST PACK_TYPE 0402
J 0
(-1200 1850);
DISPLAY 0.510638 (-1200 1850);
FORCEPROP 1 LAST $LOCATION C2318
J 0
(-1200 2150);
DISPLAY 0.510638 (-1200 2150);
FORCEPROP 1 LASTPIN (-1275 2150) $PN 1
J 2
(-1285 2130);
DISPLAY 0.787234 (-1285 2130);
PAINT MONO (-1285 2130);
FORCEPROP 1 LASTPIN (-1275 1950) $PN 2
J 2
(-1285 1930);
DISPLAY 0.787234 (-1285 1930);
PAINT MONO (-1285 1930);
FORCEPROP 2 LAST CDS_LIB pure_quanta
J 0
(-1275 2050);
DISPLAY INVISIBLE (-1275 2050);
FORCEPROP 1 LAST PATH I49
J 2
(-1325 2200);
DISPLAY 0.978723 (-1325 2200);
PAINT WHITE (-1325 2200);
DISPLAY INVISIBLE (-1325 2200);
FORCEPROP 0 LAST CDS_LOCATION C2318
J 0
(-1325 2200);
DISPLAY 1.021277 (-1325 2200);
DISPLAY INVISIBLE (-1325 2200);
FORCEPROP 0 LAST $SEC 1
J 0
(-1325 2200);
DISPLAY 0.680851 (-1325 2200);
PAINT MONO (-1325 2200);
DISPLAY INVISIBLE (-1325 2200);
FORCEPROP 0 LAST CDS_SEC 1
J 0
(-1325 2200);
DISPLAY 1.021277 (-1325 2200);
DISPLAY INVISIBLE (-1325 2200);
FORCEADD OFFPAGE..3
R 2
(-2900 -2275);
PAINT AQUA (-2900 -2275);
FORCEPROP 2 LAST $XR0 196 
J 0
(-3210 -2275);
DISPLAY 0.638298 (-3210 -2275);
PAINT MONO (-3210 -2275);
FORCEPROP 2 LAST CDS_LIB standard
J 2
(-2900 -2275);
DISPLAY INVISIBLE (-2900 -2275);
FORCEPROP 1 LAST OFFPAGE TRUE
J 2
(-3225 -2400);
DISPLAY 0.872340 (-3225 -2400);
PAINT AQUA (-3225 -2400);
DISPLAY INVISIBLE (-3225 -2400);
FORCEPROP 1 LAST COMMENT_BODY TRUE
J 2
(-2850 -2375);
DISPLAY 0.872340 (-2850 -2375);
PAINT GREEN (-2850 -2375);
DISPLAY INVISIBLE (-2850 -2375);
FORCEPROP 2 LAST PATH I5
J 0
(-3200 -2225);
DISPLAY 1.021277 (-3200 -2225);
DISPLAY INVISIBLE (-3200 -2225);
FORCEADD Q_RES..1
(-450 1475);
FORCEPROP 1 LAST PART_NUMBER CS00002JB13
J 0
(-725 1350);
DISPLAY 0.723404 (-725 1350);
PAINT WHITE (-725 1350);
DISPLAY INVISIBLE (-725 1350);
FORCEPROP 1 LAST VALUE 0
J 2
(-300 1475);
DISPLAY 0.723404 (-300 1475);
FORCEPROP 1 LAST PACK_TYPE 0402LF
J 0
(-425 1425);
DISPLAY 0.723404 (-425 1425);
FORCEPROP 1 LAST MATERIAL EMPTY
J 0
(-600 1425);
DISPLAY 0.723404 (-600 1425);
FORCEPROP 1 LAST $LOCATION R4462
J 0
(-650 1475);
DISPLAY 0.638298 (-650 1475);
FORCEPROP 1 LASTPIN (-550 1475) $PN 1
J 0
(-538 1487);
DISPLAY 0.787234 (-538 1487);
PAINT MONO (-538 1487);
FORCEPROP 1 LASTPIN (-350 1475) $PN 2
J 0
(-388 1487);
DISPLAY 0.787234 (-388 1487);
PAINT MONO (-388 1487);
FORCEPROP 1 LAST WATTAGE 1/16W
J 2
(-375 1400);
DISPLAY 0.723404 (-375 1400);
PAINT SKYBLUE (-375 1400);
DISPLAY INVISIBLE (-375 1400);
FORCEPROP 1 LAST TOLERANCE 5%
J 0
(-650 1400);
DISPLAY 0.723404 (-650 1400);
PAINT SKYBLUE (-650 1400);
DISPLAY INVISIBLE (-650 1400);
FORCEPROP 2 LAST CDS_LIB pure_quanta
J 0
(-450 1475);
DISPLAY INVISIBLE (-450 1475);
FORCEPROP 1 LAST PATH I50
J 0
(-500 1625);
DISPLAY 0.978723 (-500 1625);
PAINT WHITE (-500 1625);
DISPLAY INVISIBLE (-500 1625);
FORCEPROP 0 LAST CDS_LOCATION R4462
J 0
(-300 1525);
DISPLAY 1.021277 (-300 1525);
DISPLAY INVISIBLE (-300 1525);
FORCEPROP 0 LAST $SEC 1
J 0
(-300 1525);
DISPLAY 0.680851 (-300 1525);
PAINT MONO (-300 1525);
DISPLAY INVISIBLE (-300 1525);
FORCEPROP 0 LAST CDS_SEC 1
J 0
(-300 1525);
DISPLAY 1.021277 (-300 1525);
DISPLAY INVISIBLE (-300 1525);
FORCEADD Q_CAP..1
R 2
(-900 2050);
FORCEPROP 1 LAST PART_NUMBER CH4104K1B00
J 0
(-825 1900);
DISPLAY 0.510638 (-825 1900);
DISPLAY INVISIBLE (-825 1900);
FORCEPROP 1 LAST VALUE 0.1UF
J 0
(-825 2100);
DISPLAY 0.510638 (-825 2100);
FORCEPROP 1 LAST VOLTAGE 25V
J 0
(-825 2050);
DISPLAY 0.510638 (-825 2050);
FORCEPROP 1 LAST PACK_TYPE 0402
J 0
(-825 1850);
DISPLAY 0.510638 (-825 1850);
FORCEPROP 1 LAST TOLERANCE 10%
J 0
(-825 2000);
DISPLAY 0.510638 (-825 2000);
FORCEPROP 1 LAST MATERIAL EMPTY
J 0
(-825 1950);
DISPLAY 0.510638 (-825 1950);
FORCEPROP 1 LAST $LOCATION C2319
J 0
(-825 2150);
DISPLAY 0.510638 (-825 2150);
FORCEPROP 1 LASTPIN (-900 2150) $PN 1
J 2
(-910 2130);
DISPLAY 0.787234 (-910 2130);
PAINT MONO (-910 2130);
FORCEPROP 1 LASTPIN (-900 1950) $PN 2
J 2
(-910 1930);
DISPLAY 0.787234 (-910 1930);
PAINT MONO (-910 1930);
FORCEPROP 2 LAST CDS_LIB pure_quanta
J 0
(-900 2050);
DISPLAY INVISIBLE (-900 2050);
FORCEPROP 1 LAST PATH I51
J 2
(-950 2200);
DISPLAY 0.978723 (-950 2200);
PAINT WHITE (-950 2200);
DISPLAY INVISIBLE (-950 2200);
FORCEPROP 0 LAST CDS_LOCATION C2319
J 0
(-950 2200);
DISPLAY 1.021277 (-950 2200);
DISPLAY INVISIBLE (-950 2200);
FORCEPROP 0 LAST $SEC 1
J 0
(-950 2200);
DISPLAY 0.680851 (-950 2200);
PAINT MONO (-950 2200);
DISPLAY INVISIBLE (-950 2200);
FORCEPROP 0 LAST CDS_SEC 1
J 0
(-950 2200);
DISPLAY 1.021277 (-950 2200);
DISPLAY INVISIBLE (-950 2200);
FORCEADD Q_CAP..1
R 2
(-525 2050);
FORCEPROP 1 LAST PART_NUMBER CH4104K1B00
J 0
(-450 1900);
DISPLAY 0.510638 (-450 1900);
DISPLAY INVISIBLE (-450 1900);
FORCEPROP 1 LAST VOLTAGE 25V
J 0
(-450 2050);
DISPLAY 0.510638 (-450 2050);
FORCEPROP 1 LAST VALUE 0.1UF
J 0
(-450 2100);
DISPLAY 0.510638 (-450 2100);
FORCEPROP 1 LAST TOLERANCE 10%
J 0
(-450 2000);
DISPLAY 0.510638 (-450 2000);
FORCEPROP 1 LAST PACK_TYPE 0402
J 0
(-450 1850);
DISPLAY 0.510638 (-450 1850);
FORCEPROP 1 LAST MATERIAL EMPTY
J 0
(-450 1950);
DISPLAY 0.510638 (-450 1950);
FORCEPROP 1 LAST $LOCATION C2320
J 0
(-450 2150);
DISPLAY 0.638298 (-450 2150);
FORCEPROP 1 LASTPIN (-525 2150) $PN 1
J 2
(-535 2130);
DISPLAY 0.787234 (-535 2130);
PAINT MONO (-535 2130);
FORCEPROP 1 LASTPIN (-525 1950) $PN 2
J 2
(-535 1930);
DISPLAY 0.787234 (-535 1930);
PAINT MONO (-535 1930);
FORCEPROP 2 LAST CDS_LIB pure_quanta
J 0
(-525 2050);
DISPLAY INVISIBLE (-525 2050);
FORCEPROP 1 LAST PATH I52
J 2
(-575 2200);
DISPLAY 0.978723 (-575 2200);
PAINT WHITE (-575 2200);
DISPLAY INVISIBLE (-575 2200);
FORCEPROP 0 LAST CDS_LOCATION C2320
J 0
(-575 2200);
DISPLAY 1.021277 (-575 2200);
DISPLAY INVISIBLE (-575 2200);
FORCEPROP 0 LAST $SEC 1
J 0
(-575 2200);
DISPLAY 0.680851 (-575 2200);
PAINT MONO (-575 2200);
DISPLAY INVISIBLE (-575 2200);
FORCEPROP 0 LAST CDS_SEC 1
J 0
(-575 2200);
DISPLAY 1.021277 (-575 2200);
DISPLAY INVISIBLE (-575 2200);
FORCEADD Q_CAP..1
(-175 2050);
FORCEPROP 1 LAST PART_NUMBER CH5104KEB02
J 0
(-125 1900);
DISPLAY 0.468085 (-125 1900);
DISPLAY INVISIBLE (-125 1900);
FORCEPROP 1 LAST PACK_TYPE C0402
J 0
(-125 1850);
DISPLAY 0.468085 (-125 1850);
FORCEPROP 1 LAST MATERIAL EMPTY
J 0
(-125 1950);
DISPLAY 0.468085 (-125 1950);
FORCEPROP 1 LAST TOLERANCE 10%
J 0
(-125 2000);
DISPLAY 0.468085 (-125 2000);
FORCEPROP 1 LAST VALUE 1UF
J 0
(-125 2100);
DISPLAY 0.468085 (-125 2100);
FORCEPROP 1 LAST VOLTAGE 25V
J 0
(-125 2050);
DISPLAY 0.468085 (-125 2050);
FORCEPROP 1 LAST $LOCATION C2322
J 0
(-125 2150);
DISPLAY 0.638298 (-125 2150);
FORCEPROP 1 LASTPIN (-175 2150) $PN 1
J 0
(-165 2130);
DISPLAY 0.787234 (-165 2130);
PAINT MONO (-165 2130);
FORCEPROP 1 LASTPIN (-175 1950) $PN 2
J 0
(-165 1930);
DISPLAY 0.787234 (-165 1930);
PAINT MONO (-165 1930);
FORCEPROP 2 LAST CDS_LIB pure_quanta
J 0
(-175 2050);
DISPLAY INVISIBLE (-175 2050);
FORCEPROP 1 LAST PATH I53
J 0
(-125 2200);
DISPLAY 0.978723 (-125 2200);
PAINT WHITE (-125 2200);
DISPLAY INVISIBLE (-125 2200);
FORCEPROP 0 LAST CDS_LOCATION C2322
J 0
(-125 2200);
DISPLAY 1.021277 (-125 2200);
DISPLAY INVISIBLE (-125 2200);
FORCEPROP 0 LAST $SEC 1
J 0
(-125 2200);
DISPLAY 0.680851 (-125 2200);
PAINT MONO (-125 2200);
DISPLAY INVISIBLE (-125 2200);
FORCEPROP 0 LAST CDS_SEC 1
J 0
(-125 2200);
DISPLAY 1.021277 (-125 2200);
DISPLAY INVISIBLE (-125 2200);
FORCEADD UNIVERSAL_GND..1
(2125 -2875);
FORCEPROP 3 LASTPIN (2125 -2825) SIG_NAME GND\g
J 0
(2135 -2815);
DISPLAY 0.659574 (2135 -2815);
PAINT MONO (2135 -2815);
DISPLAY INVISIBLE (2135 -2815);
FORCEPROP 2 LAST CDS_LIB logical_power
J 0
(2125 -2875);
DISPLAY INVISIBLE (2125 -2875);
FORCEPROP 1 LAST HDL_POWER GND
J 1
(2150 -2950);
DISPLAY 0.872340 (2150 -2950);
PAINT GREEN (2150 -2950);
DISPLAY INVISIBLE (2150 -2950);
FORCEPROP 1 LAST PATH I54
J 0
(2200 -2875);
DISPLAY 0.872340 (2200 -2875);
PAINT AQUA (2200 -2875);
DISPLAY INVISIBLE (2200 -2875);
FORCEADD Q_CAP..1
(2125 -2650);
FORCEPROP 1 LAST PART_NUMBER CH4104K1B00
J 0
(2175 -2800);
DISPLAY 0.723404 (2175 -2800);
DISPLAY INVISIBLE (2175 -2800);
FORCEPROP 1 LAST MATERIAL EMPTY
J 0
(2175 -2750);
DISPLAY 0.723404 (2175 -2750);
FORCEPROP 1 LAST TOLERANCE 10%
J 0
(2175 -2700);
DISPLAY 0.723404 (2175 -2700);
FORCEPROP 1 LAST VOLTAGE 25V
J 0
(2175 -2650);
DISPLAY 0.723404 (2175 -2650);
FORCEPROP 1 LAST VALUE 0.1UF
J 0
(2175 -2600);
DISPLAY 0.723404 (2175 -2600);
FORCEPROP 1 LAST PACK_TYPE 0402
J 0
(2175 -2850);
DISPLAY 0.723404 (2175 -2850);
FORCEPROP 1 LAST $LOCATION C2325
J 0
(2175 -2550);
DISPLAY 0.723404 (2175 -2550);
FORCEPROP 1 LASTPIN (2125 -2550) $PN 1
J 0
(2135 -2570);
DISPLAY 0.723404 (2135 -2570);
PAINT MONO (2135 -2570);
FORCEPROP 1 LASTPIN (2125 -2750) $PN 2
J 0
(2135 -2770);
DISPLAY 0.723404 (2135 -2770);
PAINT MONO (2135 -2770);
FORCEPROP 2 LAST CDS_LIB pure_quanta
J 0
(2125 -2650);
DISPLAY INVISIBLE (2125 -2650);
FORCEPROP 1 LAST PATH I55
J 0
(2175 -2500);
DISPLAY 0.978723 (2175 -2500);
PAINT WHITE (2175 -2500);
DISPLAY INVISIBLE (2175 -2500);
FORCEPROP 2 LAST CDS_LOCATION C2325
J 0
(2175 -2550);
DISPLAY 0.723404 (2175 -2550);
PAINT AQUA (2175 -2550);
DISPLAY INVISIBLE (2175 -2550);
FORCEPROP 2 LAST $SEC 1
J 0
(2175 -2450);
DISPLAY 0.680851 (2175 -2450);
PAINT MONO (2175 -2450);
DISPLAY INVISIBLE (2175 -2450);
FORCEPROP 0 LAST CDS_SEC 1
J 0
(2175 -2500);
DISPLAY INVISIBLE (2175 -2500);
FORCEADD Q_CAP..1
(925 -1725);
FORCEPROP 1 LAST PART_NUMBER CH5104KEB02
J 0
(975 -1875);
DISPLAY 0.723404 (975 -1875);
DISPLAY INVISIBLE (975 -1875);
FORCEPROP 1 LAST MATERIAL EMPTY
J 0
(975 -1825);
DISPLAY 0.723404 (975 -1825);
FORCEPROP 1 LAST PACK_TYPE C0402
J 0
(975 -1925);
DISPLAY 0.723404 (975 -1925);
FORCEPROP 1 LAST VALUE 1UF
J 0
(975 -1675);
DISPLAY 0.723404 (975 -1675);
FORCEPROP 1 LAST VOLTAGE 25V
J 0
(975 -1725);
DISPLAY 0.723404 (975 -1725);
FORCEPROP 1 LAST TOLERANCE 10%
J 0
(975 -1775);
DISPLAY 0.723404 (975 -1775);
FORCEPROP 1 LAST $LOCATION C2323
J 0
(975 -1625);
DISPLAY 0.723404 (975 -1625);
FORCEPROP 1 LASTPIN (925 -1625) $PN 1
J 0
(935 -1645);
DISPLAY 0.723404 (935 -1645);
PAINT MONO (935 -1645);
FORCEPROP 1 LASTPIN (925 -1825) $PN 2
J 0
(935 -1845);
DISPLAY 0.723404 (935 -1845);
PAINT MONO (935 -1845);
FORCEPROP 2 LAST CDS_LIB pure_quanta
J 0
(925 -1725);
DISPLAY INVISIBLE (925 -1725);
FORCEPROP 1 LAST PATH I56
J 0
(975 -1575);
DISPLAY 0.978723 (975 -1575);
PAINT WHITE (975 -1575);
DISPLAY INVISIBLE (975 -1575);
FORCEPROP 2 LAST CDS_LOCATION C2323
J 0
(975 -1625);
DISPLAY 0.723404 (975 -1625);
PAINT AQUA (975 -1625);
DISPLAY INVISIBLE (975 -1625);
FORCEPROP 2 LAST $SEC 1
J 0
(975 -1525);
DISPLAY 0.680851 (975 -1525);
PAINT MONO (975 -1525);
DISPLAY INVISIBLE (975 -1525);
FORCEPROP 0 LAST CDS_SEC 1
J 0
(975 -1525);
DISPLAY 0.680851 (975 -1525);
PAINT MONO (975 -1525);
DISPLAY INVISIBLE (975 -1525);
FORCEADD UNIVERSAL_GND..1
(1375 -2075);
FORCEPROP 3 LASTPIN (1375 -2025) SIG_NAME GND\g
J 0
(1385 -2015);
DISPLAY 0.659574 (1385 -2015);
PAINT MONO (1385 -2015);
DISPLAY INVISIBLE (1385 -2015);
FORCEPROP 2 LAST CDS_LIB logical_power
J 0
(1375 -2075);
DISPLAY INVISIBLE (1375 -2075);
FORCEPROP 1 LAST HDL_POWER GND
J 1
(1400 -2150);
DISPLAY 0.872340 (1400 -2150);
PAINT GREEN (1400 -2150);
DISPLAY INVISIBLE (1400 -2150);
FORCEPROP 1 LAST PATH I57
J 0
(1450 -2075);
DISPLAY 0.872340 (1450 -2075);
PAINT AQUA (1450 -2075);
DISPLAY INVISIBLE (1450 -2075);
FORCEADD Q_CAP..1
(1375 -1725);
FORCEPROP 1 LAST PART_NUMBER CH4104K1B00
J 0
(1425 -1875);
DISPLAY 0.723404 (1425 -1875);
DISPLAY INVISIBLE (1425 -1875);
FORCEPROP 1 LAST VALUE 0.1UF
J 0
(1425 -1675);
DISPLAY 0.723404 (1425 -1675);
FORCEPROP 1 LAST VOLTAGE 25V
J 0
(1425 -1725);
DISPLAY 0.723404 (1425 -1725);
FORCEPROP 1 LAST TOLERANCE 10%
J 0
(1425 -1775);
DISPLAY 0.723404 (1425 -1775);
FORCEPROP 1 LAST MATERIAL EMPTY
J 0
(1425 -1825);
DISPLAY 0.723404 (1425 -1825);
FORCEPROP 1 LAST PACK_TYPE 0402
J 0
(1425 -1925);
DISPLAY 0.723404 (1425 -1925);
FORCEPROP 1 LAST $LOCATION C2324
J 0
(1425 -1625);
DISPLAY 0.723404 (1425 -1625);
FORCEPROP 1 LASTPIN (1375 -1625) $PN 1
J 0
(1385 -1645);
DISPLAY 0.723404 (1385 -1645);
PAINT MONO (1385 -1645);
FORCEPROP 1 LASTPIN (1375 -1825) $PN 2
J 0
(1385 -1845);
DISPLAY 0.723404 (1385 -1845);
PAINT MONO (1385 -1845);
FORCEPROP 2 LAST CDS_LIB pure_quanta
J 0
(1375 -1725);
DISPLAY INVISIBLE (1375 -1725);
FORCEPROP 1 LAST PATH I58
J 0
(1425 -1575);
DISPLAY 0.978723 (1425 -1575);
PAINT WHITE (1425 -1575);
DISPLAY INVISIBLE (1425 -1575);
FORCEPROP 2 LAST CDS_LOCATION C2324
J 0
(1425 -1625);
DISPLAY 0.723404 (1425 -1625);
PAINT AQUA (1425 -1625);
DISPLAY INVISIBLE (1425 -1625);
FORCEPROP 2 LAST $SEC 1
J 0
(1425 -1525);
DISPLAY 0.680851 (1425 -1525);
PAINT MONO (1425 -1525);
DISPLAY INVISIBLE (1425 -1525);
FORCEPROP 0 LAST CDS_SEC 1
J 0
(1425 -1575);
DISPLAY INVISIBLE (1425 -1575);
FORCEADD UNIVERSAL_GND..1
(2025 -2600);
FORCEPROP 3 LASTPIN (2025 -2550) SIG_NAME GND\g
J 0
(2035 -2540);
DISPLAY 0.659574 (2035 -2540);
PAINT MONO (2035 -2540);
DISPLAY INVISIBLE (2035 -2540);
FORCEPROP 2 LAST CDS_LIB logical_power
J 0
(2025 -2600);
DISPLAY INVISIBLE (2025 -2600);
FORCEPROP 1 LAST HDL_POWER GND
J 1
(2050 -2675);
DISPLAY 0.872340 (2050 -2675);
PAINT GREEN (2050 -2675);
DISPLAY INVISIBLE (2050 -2675);
FORCEPROP 1 LAST PATH I59
J 0
(2100 -2600);
DISPLAY 0.872340 (2100 -2600);
PAINT AQUA (2100 -2600);
DISPLAY INVISIBLE (2100 -2600);
FORCEADD OFFPAGE..3
R 2
(-2900 -2225);
PAINT AQUA (-2900 -2225);
FORCEPROP 2 LAST $XR0 196 
J 0
(-3210 -2225);
DISPLAY 0.638298 (-3210 -2225);
PAINT MONO (-3210 -2225);
FORCEPROP 2 LAST CDS_LIB standard
J 2
(-2900 -2225);
DISPLAY INVISIBLE (-2900 -2225);
FORCEPROP 1 LAST OFFPAGE TRUE
J 2
(-3225 -2350);
DISPLAY 0.872340 (-3225 -2350);
PAINT AQUA (-3225 -2350);
DISPLAY INVISIBLE (-3225 -2350);
FORCEPROP 1 LAST COMMENT_BODY TRUE
J 2
(-2850 -2325);
DISPLAY 0.872340 (-2850 -2325);
PAINT GREEN (-2850 -2325);
DISPLAY INVISIBLE (-2850 -2325);
FORCEPROP 2 LAST PATH I6
J 0
(-3200 -2175);
DISPLAY 1.021277 (-3200 -2175);
DISPLAY INVISIBLE (-3200 -2175);
FORCEADD Q_RES..1
(2250 -2275);
FORCEPROP 1 LAST PART_NUMBER CS00002JB13
J 0
(1975 -2400);
DISPLAY 0.723404 (1975 -2400);
PAINT WHITE (1975 -2400);
DISPLAY INVISIBLE (1975 -2400);
FORCEPROP 1 LAST PACK_TYPE 0402LF
J 0
(2675 -2275);
DISPLAY 0.723404 (2675 -2275);
FORCEPROP 1 LAST MATERIAL CHIP
J 0
(2500 -2275);
DISPLAY 0.723404 (2500 -2275);
FORCEPROP 1 LAST VALUE 0
J 2
(2400 -2275);
DISPLAY 0.723404 (2400 -2275);
FORCEPROP 1 LAST $LOCATION R4468
J 0
(2000 -2275);
DISPLAY 0.723404 (2000 -2275);
FORCEPROP 1 LASTPIN (2150 -2275) $PN 1
J 0
(2162 -2263);
DISPLAY 0.723404 (2162 -2263);
PAINT MONO (2162 -2263);
FORCEPROP 1 LASTPIN (2350 -2275) $PN 2
J 0
(2312 -2263);
DISPLAY 0.723404 (2312 -2263);
PAINT MONO (2312 -2263);
FORCEPROP 1 LAST WATTAGE 1/16W
J 2
(2325 -2350);
DISPLAY 0.723404 (2325 -2350);
PAINT SKYBLUE (2325 -2350);
DISPLAY INVISIBLE (2325 -2350);
FORCEPROP 1 LAST TOLERANCE 5%
J 0
(2050 -2350);
DISPLAY 0.723404 (2050 -2350);
PAINT SKYBLUE (2050 -2350);
DISPLAY INVISIBLE (2050 -2350);
FORCEPROP 2 LAST CDS_LIB pure_quanta
J 0
(2250 -2275);
DISPLAY INVISIBLE (2250 -2275);
FORCEPROP 1 LAST PATH I60
J 0
(2200 -2125);
DISPLAY 0.978723 (2200 -2125);
PAINT WHITE (2200 -2125);
DISPLAY INVISIBLE (2200 -2125);
FORCEPROP 2 LAST CDS_LOCATION R4468
J 0
(2000 -2275);
DISPLAY 0.723404 (2000 -2275);
PAINT AQUA (2000 -2275);
DISPLAY INVISIBLE (2000 -2275);
FORCEPROP 2 LAST $SEC 1
J 0
(2200 -2075);
DISPLAY 0.680851 (2200 -2075);
PAINT MONO (2200 -2075);
DISPLAY INVISIBLE (2200 -2075);
FORCEPROP 2 LAST CDS_SEC 1
J 0
(2200 -2075);
DISPLAY 1.021277 (2200 -2075);
DISPLAY INVISIBLE (2200 -2075);
FORCEADD Q_RES..1
(2250 -2225);
FORCEPROP 1 LAST PART_NUMBER CS00002JB13
J 0
(1975 -2350);
DISPLAY 0.723404 (1975 -2350);
PAINT WHITE (1975 -2350);
DISPLAY INVISIBLE (1975 -2350);
FORCEPROP 1 LAST PACK_TYPE 0402LF
J 0
(2675 -2225);
DISPLAY 0.723404 (2675 -2225);
FORCEPROP 1 LAST VALUE 0
J 2
(2400 -2225);
DISPLAY 0.723404 (2400 -2225);
FORCEPROP 1 LAST MATERIAL CHIP
J 0
(2500 -2225);
DISPLAY 0.723404 (2500 -2225);
FORCEPROP 1 LAST $LOCATION R4467
J 0
(2000 -2225);
DISPLAY 0.723404 (2000 -2225);
FORCEPROP 1 LASTPIN (2150 -2225) $PN 1
J 0
(2162 -2213);
DISPLAY 0.723404 (2162 -2213);
PAINT MONO (2162 -2213);
FORCEPROP 1 LASTPIN (2350 -2225) $PN 2
J 0
(2312 -2213);
DISPLAY 0.723404 (2312 -2213);
PAINT MONO (2312 -2213);
FORCEPROP 1 LAST WATTAGE 1/16W
J 2
(2325 -2300);
DISPLAY 0.723404 (2325 -2300);
PAINT SKYBLUE (2325 -2300);
DISPLAY INVISIBLE (2325 -2300);
FORCEPROP 1 LAST TOLERANCE 5%
J 0
(2050 -2300);
DISPLAY 0.723404 (2050 -2300);
PAINT SKYBLUE (2050 -2300);
DISPLAY INVISIBLE (2050 -2300);
FORCEPROP 2 LAST CDS_LIB pure_quanta
J 0
(2250 -2225);
DISPLAY INVISIBLE (2250 -2225);
FORCEPROP 1 LAST PATH I61
J 0
(2200 -2075);
DISPLAY 0.978723 (2200 -2075);
PAINT WHITE (2200 -2075);
DISPLAY INVISIBLE (2200 -2075);
FORCEPROP 2 LAST CDS_LOCATION R4467
J 0
(2000 -2225);
DISPLAY 0.723404 (2000 -2225);
PAINT AQUA (2000 -2225);
DISPLAY INVISIBLE (2000 -2225);
FORCEPROP 2 LAST $SEC 1
J 0
(2200 -2025);
DISPLAY 0.680851 (2200 -2025);
PAINT MONO (2200 -2025);
DISPLAY INVISIBLE (2200 -2025);
FORCEPROP 2 LAST CDS_SEC 1
J 0
(2200 -2025);
DISPLAY 1.021277 (2200 -2025);
DISPLAY INVISIBLE (2200 -2025);
FORCEADD UNIVERSAL_POWER..1
R 2
(1800 -1400);
FORCEPROP 3 LASTPIN (1800 -1450) SIG_NAME P3V3_AUX\g
J 0
(1810 -1440);
DISPLAY 0.659574 (1810 -1440);
PAINT MONO (1810 -1440);
DISPLAY INVISIBLE (1810 -1440);
FORCEPROP 1 LAST HDL_POWER P3V3_AUX
J 1
(1800 -1350);
DISPLAY 0.723404 (1800 -1350);
PAINT GREEN (1800 -1350);
FORCEPROP 2 LAST CDS_LIB logical_power
J 0
(1800 -1400);
DISPLAY INVISIBLE (1800 -1400);
FORCEPROP 1 LAST PATH I62
J 2
(1750 -1375);
DISPLAY 0.872340 (1750 -1375);
PAINT AQUA (1750 -1375);
DISPLAY INVISIBLE (1750 -1375);
FORCEADD UNIVERSAL_GND..1
(1375 675);
FORCEPROP 3 LASTPIN (1375 725) SIG_NAME GND\g
J 0
(1385 735);
DISPLAY 0.659574 (1385 735);
PAINT MONO (1385 735);
DISPLAY INVISIBLE (1385 735);
FORCEPROP 2 LAST CDS_LIB logical_power
J 0
(1375 675);
DISPLAY INVISIBLE (1375 675);
FORCEPROP 1 LAST HDL_POWER GND
J 1
(1400 600);
DISPLAY 0.872340 (1400 600);
PAINT GREEN (1400 600);
DISPLAY INVISIBLE (1400 600);
FORCEPROP 1 LAST PATH I63
J 0
(1450 675);
DISPLAY 0.872340 (1450 675);
PAINT AQUA (1450 675);
DISPLAY INVISIBLE (1450 675);
FORCEADD OFFPAGE..6
R 2
(2325 1375);
PAINT AQUA (2325 1375);
FORCEPROP 2 LAST $XR0 196 
J 0
(2539 1375);
DISPLAY 0.638298 (2539 1375);
PAINT MONO (2539 1375);
FORCEPROP 2 LAST CDS_LIB standard
J 2
(2325 1375);
DISPLAY INVISIBLE (2325 1375);
FORCEPROP 1 LAST OFFPAGE TRUE
J 2
(2000 1250);
DISPLAY 0.872340 (2000 1250);
PAINT AQUA (2000 1250);
DISPLAY INVISIBLE (2000 1250);
FORCEPROP 1 LAST COMMENT_BODY TRUE
J 2
(2225 1300);
DISPLAY 1.170213 (2225 1300);
PAINT GREEN (2225 1300);
DISPLAY INVISIBLE (2225 1300);
FORCEPROP 2 LAST PATH I64
J 0
(2550 1425);
DISPLAY 1.021277 (2550 1425);
DISPLAY INVISIBLE (2550 1425);
FORCEADD OFFPAGE..6
R 2
(2325 1325);
PAINT AQUA (2325 1325);
FORCEPROP 2 LAST $XR0 196 
J 0
(2539 1325);
DISPLAY 0.638298 (2539 1325);
PAINT MONO (2539 1325);
FORCEPROP 2 LAST CDS_LIB standard
J 2
(2325 1325);
DISPLAY INVISIBLE (2325 1325);
FORCEPROP 1 LAST OFFPAGE TRUE
J 2
(2000 1200);
DISPLAY 0.872340 (2000 1200);
PAINT AQUA (2000 1200);
DISPLAY INVISIBLE (2000 1200);
FORCEPROP 1 LAST COMMENT_BODY TRUE
J 2
(2225 1250);
DISPLAY 1.170213 (2225 1250);
PAINT GREEN (2225 1250);
DISPLAY INVISIBLE (2225 1250);
FORCEPROP 2 LAST PATH I65
J 0
(2550 1375);
DISPLAY 1.021277 (2550 1375);
DISPLAY INVISIBLE (2550 1375);
FORCEADD OFFPAGE..3
(3975 -2275);
PAINT AQUA (3975 -2275);
FORCEPROP 2 LAST $XR0 240 
J 0
(4189 -2275);
DISPLAY 0.638298 (4189 -2275);
PAINT MONO (4189 -2275);
FORCEPROP 2 LAST CDS_LIB standard
J 0
(3975 -2275);
DISPLAY INVISIBLE (3975 -2275);
FORCEPROP 1 LAST OFFPAGE TRUE
J 0
(4300 -2400);
DISPLAY 0.872340 (4300 -2400);
PAINT AQUA (4300 -2400);
DISPLAY INVISIBLE (4300 -2400);
FORCEPROP 1 LAST COMMENT_BODY TRUE
J 0
(3925 -2375);
DISPLAY 0.872340 (3925 -2375);
PAINT GREEN (3925 -2375);
DISPLAY INVISIBLE (3925 -2375);
FORCEPROP 2 LAST PATH I66
J 0
(4200 -2225);
DISPLAY 1.021277 (4200 -2225);
DISPLAY INVISIBLE (4200 -2225);
FORCEADD OFFPAGE..3
(3975 -2225);
PAINT AQUA (3975 -2225);
FORCEPROP 2 LAST $XR0 240 
J 0
(4189 -2225);
DISPLAY 0.638298 (4189 -2225);
PAINT MONO (4189 -2225);
FORCEPROP 2 LAST CDS_LIB standard
J 0
(3975 -2225);
DISPLAY INVISIBLE (3975 -2225);
FORCEPROP 1 LAST OFFPAGE TRUE
J 0
(4300 -2350);
DISPLAY 0.872340 (4300 -2350);
PAINT AQUA (4300 -2350);
DISPLAY INVISIBLE (4300 -2350);
FORCEPROP 1 LAST COMMENT_BODY TRUE
J 0
(3925 -2325);
DISPLAY 0.872340 (3925 -2325);
PAINT GREEN (3925 -2325);
DISPLAY INVISIBLE (3925 -2325);
FORCEPROP 2 LAST PATH I67
J 0
(4200 -2175);
DISPLAY 1.021277 (4200 -2175);
DISPLAY INVISIBLE (4200 -2175);
FORCEADD UNIVERSAL_GND..1
(-3500 -525);
FORCEPROP 3 LASTPIN (-3500 -475) SIG_NAME GND\g
J 0
(-3490 -465);
DISPLAY 0.659574 (-3490 -465);
PAINT MONO (-3490 -465);
DISPLAY INVISIBLE (-3490 -465);
FORCEPROP 2 LAST CDS_LIB logical_power
J 0
(-3500 -525);
DISPLAY INVISIBLE (-3500 -525);
FORCEPROP 1 LAST HDL_POWER GND
J 1
(-3475 -600);
DISPLAY 0.872340 (-3475 -600);
PAINT GREEN (-3475 -600);
DISPLAY INVISIBLE (-3475 -600);
FORCEPROP 1 LAST PATH I7
J 0
(-3425 -525);
DISPLAY 0.872340 (-3425 -525);
PAINT AQUA (-3425 -525);
DISPLAY INVISIBLE (-3425 -525);
FORCEADD Q_RES..2
(3475 1200);
FORCEPROP 1 LAST PART_NUMBER CS00002JB13
J 0
(3525 1025);
DISPLAY 0.510638 (3525 1025);
DISPLAY INVISIBLE (3525 1025);
FORCEPROP 1 LAST PACK_TYPE 0402LF
J 0
(3525 975);
DISPLAY 0.510638 (3525 975);
FORCEPROP 1 LAST WATTAGE 1/16W
J 0
(3525 1125);
DISPLAY 0.510638 (3525 1125);
FORCEPROP 1 LAST MATERIAL CHIP
J 0
(3525 1075);
DISPLAY 0.510638 (3525 1075);
FORCEPROP 1 LAST TOLERANCE 5%
J 0
(3530 1175);
DISPLAY 0.510638 (3530 1175);
FORCEPROP 1 LAST VALUE 0
J 0
(3530 1225);
DISPLAY 0.510638 (3530 1225);
FORCEPROP 1 LAST $LOCATION R4474
J 0
(3530 1275);
DISPLAY 0.510638 (3530 1275);
FORCEPROP 1 LASTPIN (3475 1300) $PN 1
J 0
(3480 1262);
DISPLAY 0.787234 (3480 1262);
PAINT MONO (3480 1262);
FORCEPROP 1 LASTPIN (3475 1100) $PN 2
J 0
(3480 1110);
DISPLAY 0.787234 (3480 1110);
PAINT MONO (3480 1110);
FORCEPROP 2 LAST CDS_LIB pure_quanta
J 0
(3475 1200);
DISPLAY INVISIBLE (3475 1200);
FORCEPROP 1 LAST PATH I72
J 0
(3525 1375);
DISPLAY 0.978723 (3525 1375);
PAINT WHITE (3525 1375);
DISPLAY INVISIBLE (3525 1375);
FORCEPROP 2 LAST CDS_LOCATION R4474
J 0
(3525 1450);
DISPLAY 1.021277 (3525 1450);
DISPLAY INVISIBLE (3525 1450);
FORCEPROP 2 LAST $SEC 1
J 0
(3525 1450);
DISPLAY 0.680851 (3525 1450);
PAINT MONO (3525 1450);
DISPLAY INVISIBLE (3525 1450);
FORCEPROP 2 LAST CDS_SEC 1
J 0
(3525 1450);
DISPLAY 1.021277 (3525 1450);
DISPLAY INVISIBLE (3525 1450);
FORCEADD Q_RES..2
(3375 1200);
FORCEPROP 1 LAST PART_NUMBER CS00002JB13
J 0
(3395 1150);
DISPLAY 0.510638 (3395 1150);
DISPLAY INVISIBLE (3395 1150);
FORCEPROP 1 LAST MATERIAL CHIP
J 0
(3250 1075);
DISPLAY 0.510638 (3250 1075);
FORCEPROP 1 LAST VALUE 0
J 0
(3325 1225);
DISPLAY 0.510638 (3325 1225);
FORCEPROP 1 LAST $LOCATION R4473
J 0
(3275 1275);
DISPLAY 0.510638 (3275 1275);
FORCEPROP 1 LASTPIN (3375 1300) $PN 1
J 0
(3380 1262);
DISPLAY 0.787234 (3380 1262);
PAINT MONO (3380 1262);
FORCEPROP 1 LASTPIN (3375 1100) $PN 2
J 0
(3380 1110);
DISPLAY 0.787234 (3380 1110);
PAINT MONO (3380 1110);
FORCEPROP 1 LAST WATTAGE 1/16W
J 0
(3395 1250);
DISPLAY 0.510638 (3395 1250);
DISPLAY INVISIBLE (3395 1250);
FORCEPROP 1 LAST TOLERANCE 5%
J 0
(3400 1300);
DISPLAY 0.510638 (3400 1300);
DISPLAY INVISIBLE (3400 1300);
FORCEPROP 1 LAST PACK_TYPE 0402LF
J 0
(3395 1100);
DISPLAY 0.510638 (3395 1100);
DISPLAY INVISIBLE (3395 1100);
FORCEPROP 2 LAST CDS_LIB pure_quanta
J 0
(3375 1200);
DISPLAY INVISIBLE (3375 1200);
FORCEPROP 1 LAST PATH I73
J 0
(3425 1375);
DISPLAY 0.978723 (3425 1375);
PAINT WHITE (3425 1375);
DISPLAY INVISIBLE (3425 1375);
FORCEPROP 2 LAST CDS_LOCATION R4473
J 0
(3425 1425);
DISPLAY 1.021277 (3425 1425);
DISPLAY INVISIBLE (3425 1425);
FORCEPROP 2 LAST $SEC 1
J 0
(3425 1425);
DISPLAY 0.680851 (3425 1425);
PAINT MONO (3425 1425);
DISPLAY INVISIBLE (3425 1425);
FORCEPROP 2 LAST CDS_SEC 1
J 0
(3425 1425);
DISPLAY 1.021277 (3425 1425);
DISPLAY INVISIBLE (3425 1425);
FORCEADD OFFPAGE..3
(4250 1425);
PAINT AQUA (4250 1425);
FORCEPROP 2 LAST $XR0 180 
J 0
(4464 1425);
DISPLAY 0.638298 (4464 1425);
PAINT MONO (4464 1425);
FORCEPROP 2 LAST CDS_LIB standard
J 0
(4250 1425);
DISPLAY INVISIBLE (4250 1425);
FORCEPROP 1 LAST OFFPAGE TRUE
J 0
(4575 1300);
DISPLAY 0.872340 (4575 1300);
PAINT AQUA (4575 1300);
DISPLAY INVISIBLE (4575 1300);
FORCEPROP 1 LAST COMMENT_BODY TRUE
J 0
(4200 1325);
DISPLAY 0.872340 (4200 1325);
PAINT GREEN (4200 1325);
DISPLAY INVISIBLE (4200 1325);
FORCEPROP 2 LAST PATH I74
J 0
(4475 1475);
DISPLAY 1.021277 (4475 1475);
DISPLAY INVISIBLE (4475 1475);
FORCEADD Q_RES..1
(2125 1825);
FORCEPROP 1 LAST PART_NUMBER CS00002JB13
J 0
(1850 1700);
DISPLAY 0.723404 (1850 1700);
PAINT WHITE (1850 1700);
DISPLAY INVISIBLE (1850 1700);
FORCEPROP 1 LAST PACK_TYPE 0402LF
J 0
(2300 1825);
DISPLAY 0.723404 (2300 1825);
FORCEPROP 1 LAST MATERIAL EMPTY
J 0
(2300 1775);
DISPLAY 0.723404 (2300 1775);
FORCEPROP 1 LAST VALUE 0
J 2
(2275 1825);
DISPLAY 0.723404 (2275 1825);
FORCEPROP 1 LAST $LOCATION R4466
J 0
(1875 1825);
DISPLAY 0.638298 (1875 1825);
FORCEPROP 1 LASTPIN (2025 1825) $PN 1
J 0
(2037 1837);
DISPLAY 0.787234 (2037 1837);
PAINT MONO (2037 1837);
FORCEPROP 1 LASTPIN (2225 1825) $PN 2
J 0
(2187 1837);
DISPLAY 0.787234 (2187 1837);
PAINT MONO (2187 1837);
FORCEPROP 1 LAST WATTAGE 1/16W
J 2
(2200 1750);
DISPLAY 0.723404 (2200 1750);
PAINT SKYBLUE (2200 1750);
DISPLAY INVISIBLE (2200 1750);
FORCEPROP 1 LAST TOLERANCE 5%
J 0
(1925 1750);
DISPLAY 0.723404 (1925 1750);
PAINT SKYBLUE (1925 1750);
DISPLAY INVISIBLE (1925 1750);
FORCEPROP 2 LAST CDS_LIB pure_quanta
J 0
(2125 1825);
DISPLAY INVISIBLE (2125 1825);
FORCEPROP 1 LAST PATH I75
J 0
(2075 1975);
DISPLAY 0.978723 (2075 1975);
PAINT WHITE (2075 1975);
DISPLAY INVISIBLE (2075 1975);
FORCEPROP 0 LAST CDS_LOCATION R4466
J 0
(2300 1875);
DISPLAY 1.021277 (2300 1875);
DISPLAY INVISIBLE (2300 1875);
FORCEPROP 0 LAST $SEC 1
J 0
(2300 1875);
DISPLAY 0.680851 (2300 1875);
PAINT MONO (2300 1875);
DISPLAY INVISIBLE (2300 1875);
FORCEPROP 0 LAST CDS_SEC 1
J 0
(2300 1875);
DISPLAY 1.021277 (2300 1875);
DISPLAY INVISIBLE (2300 1875);
FORCEADD UNIVERSAL_GND..1
R 1
(2675 1825);
FORCEPROP 3 LASTPIN (2625 1825) SIG_NAME GND\g
J 0
(2635 1835);
DISPLAY 0.659574 (2635 1835);
PAINT MONO (2635 1835);
DISPLAY INVISIBLE (2635 1835);
FORCEPROP 2 LAST CDS_LIB logical_power
J 0
(2675 1825);
DISPLAY INVISIBLE (2675 1825);
FORCEPROP 1 LAST HDL_POWER GND
R 1
J 1
(2750 1850);
DISPLAY 0.872340 (2750 1850);
PAINT GREEN (2750 1850);
DISPLAY INVISIBLE (2750 1850);
FORCEPROP 1 LAST PATH I76
R 1
J 0
(2675 1900);
DISPLAY 0.872340 (2675 1900);
PAINT AQUA (2675 1900);
DISPLAY INVISIBLE (2675 1900);
FORCEADD Q_RES..1
(3200 1475);
FORCEPROP 1 LAST PART_NUMBER CS00002JB13
J 0
(2925 1350);
DISPLAY 0.723404 (2925 1350);
PAINT WHITE (2925 1350);
DISPLAY INVISIBLE (2925 1350);
FORCEPROP 1 LAST PACK_TYPE 0402LF
J 0
(2725 1475);
DISPLAY 0.723404 (2725 1475);
FORCEPROP 1 LAST VALUE 0
J 2
(3350 1475);
DISPLAY 0.723404 (3350 1475);
FORCEPROP 1 LAST MATERIAL EMPTY
J 0
(2550 1475);
DISPLAY 0.723404 (2550 1475);
FORCEPROP 1 LAST $LOCATION R4471
J 0
(2950 1475);
DISPLAY 0.723404 (2950 1475);
FORCEPROP 1 LASTPIN (3100 1475) $PN 1
J 0
(3112 1487);
DISPLAY 0.723404 (3112 1487);
PAINT MONO (3112 1487);
FORCEPROP 1 LASTPIN (3300 1475) $PN 2
J 0
(3262 1487);
DISPLAY 0.723404 (3262 1487);
PAINT MONO (3262 1487);
FORCEPROP 1 LAST WATTAGE 1/16W
J 2
(3275 1400);
DISPLAY 0.723404 (3275 1400);
PAINT SKYBLUE (3275 1400);
DISPLAY INVISIBLE (3275 1400);
FORCEPROP 1 LAST TOLERANCE 5%
J 0
(3000 1400);
DISPLAY 0.723404 (3000 1400);
PAINT SKYBLUE (3000 1400);
DISPLAY INVISIBLE (3000 1400);
FORCEPROP 2 LAST CDS_LIB pure_quanta
J 0
(3200 1475);
DISPLAY INVISIBLE (3200 1475);
FORCEPROP 1 LAST PATH I77
J 0
(3150 1625);
DISPLAY 0.978723 (3150 1625);
PAINT WHITE (3150 1625);
DISPLAY INVISIBLE (3150 1625);
FORCEPROP 2 LAST CDS_LOCATION R4471
J 0
(3150 1675);
DISPLAY 1.021277 (3150 1675);
DISPLAY INVISIBLE (3150 1675);
FORCEPROP 2 LAST $SEC 1
J 0
(3150 1675);
DISPLAY 0.680851 (3150 1675);
PAINT MONO (3150 1675);
DISPLAY INVISIBLE (3150 1675);
FORCEPROP 2 LAST CDS_SEC 1
J 0
(3150 1675);
DISPLAY 1.021277 (3150 1675);
DISPLAY INVISIBLE (3150 1675);
FORCEADD Q_RES..1
(3200 1425);
FORCEPROP 1 LAST PART_NUMBER CS00002JB13
J 0
(2925 1300);
DISPLAY 0.723404 (2925 1300);
PAINT WHITE (2925 1300);
DISPLAY INVISIBLE (2925 1300);
FORCEPROP 1 LAST MATERIAL EMPTY
J 0
(2550 1425);
DISPLAY 0.723404 (2550 1425);
FORCEPROP 1 LAST VALUE 0
J 2
(3350 1425);
DISPLAY 0.723404 (3350 1425);
FORCEPROP 1 LAST PACK_TYPE 0402LF
J 0
(2725 1425);
DISPLAY 0.723404 (2725 1425);
FORCEPROP 1 LAST $LOCATION R4472
J 0
(2950 1425);
DISPLAY 0.723404 (2950 1425);
FORCEPROP 1 LASTPIN (3100 1425) $PN 1
J 0
(3112 1437);
DISPLAY 0.723404 (3112 1437);
PAINT MONO (3112 1437);
FORCEPROP 1 LASTPIN (3300 1425) $PN 2
J 0
(3262 1437);
DISPLAY 0.723404 (3262 1437);
PAINT MONO (3262 1437);
FORCEPROP 1 LAST TOLERANCE 5%
J 0
(3000 1350);
DISPLAY 0.723404 (3000 1350);
PAINT SKYBLUE (3000 1350);
DISPLAY INVISIBLE (3000 1350);
FORCEPROP 1 LAST WATTAGE 1/16W
J 2
(3275 1350);
DISPLAY 0.723404 (3275 1350);
PAINT SKYBLUE (3275 1350);
DISPLAY INVISIBLE (3275 1350);
FORCEPROP 2 LAST CDS_LIB pure_quanta
J 0
(3200 1425);
DISPLAY INVISIBLE (3200 1425);
FORCEPROP 1 LAST PATH I78
J 0
(3150 1575);
DISPLAY 0.978723 (3150 1575);
PAINT WHITE (3150 1575);
DISPLAY INVISIBLE (3150 1575);
FORCEPROP 2 LAST CDS_LOCATION R4472
J 0
(3150 1625);
DISPLAY 1.021277 (3150 1625);
DISPLAY INVISIBLE (3150 1625);
FORCEPROP 2 LAST $SEC 1
J 0
(3150 1625);
DISPLAY 0.680851 (3150 1625);
PAINT MONO (3150 1625);
DISPLAY INVISIBLE (3150 1625);
FORCEPROP 2 LAST CDS_SEC 1
J 0
(3150 1625);
DISPLAY 1.021277 (3150 1625);
DISPLAY INVISIBLE (3150 1625);
FORCEADD OFFPAGE..3
(4250 1475);
PAINT AQUA (4250 1475);
FORCEPROP 2 LAST $XR0 180 
J 0
(4464 1475);
DISPLAY 0.638298 (4464 1475);
PAINT MONO (4464 1475);
FORCEPROP 2 LAST CDS_LIB standard
J 0
(4250 1475);
DISPLAY INVISIBLE (4250 1475);
FORCEPROP 1 LAST OFFPAGE TRUE
J 0
(4575 1350);
DISPLAY 0.872340 (4575 1350);
PAINT AQUA (4575 1350);
DISPLAY INVISIBLE (4575 1350);
FORCEPROP 1 LAST COMMENT_BODY TRUE
J 0
(4200 1375);
DISPLAY 0.872340 (4200 1375);
PAINT GREEN (4200 1375);
DISPLAY INVISIBLE (4200 1375);
FORCEPROP 2 LAST PATH I79
J 0
(4475 1525);
DISPLAY 1.021277 (4475 1525);
DISPLAY INVISIBLE (4475 1525);
FORCEADD Q_RES..2
(-3500 -100);
FORCEPROP 1 LAST PART_NUMBER CS31002FB08
J 0
(-3460 -225);
DISPLAY 0.723404 (-3460 -225);
PAINT WHITE (-3460 -225);
DISPLAY INVISIBLE (-3460 -225);
FORCEPROP 1 LAST PACK_TYPE 0402LF
J 0
(-3460 -275);
DISPLAY 0.723404 (-3460 -275);
PAINT SKYBLUE (-3460 -275);
FORCEPROP 1 LAST MATERIAL EMPTY
J 0
(-3460 -175);
DISPLAY 0.723404 (-3460 -175);
PAINT RED (-3460 -175);
FORCEPROP 1 LAST TOLERANCE 1%
J 0
(-3455 -75);
DISPLAY 0.723404 (-3455 -75);
PAINT SKYBLUE (-3455 -75);
FORCEPROP 1 LAST VALUE 10K
J 0
(-3455 -25);
DISPLAY 0.723404 (-3455 -25);
PAINT SKYBLUE (-3455 -25);
FORCEPROP 1 LAST WATTAGE 1/16W
J 0
(-3460 -125);
DISPLAY 0.723404 (-3460 -125);
PAINT SKYBLUE (-3460 -125);
FORCEPROP 1 LAST $LOCATION R4449
J 0
(-3455 25);
DISPLAY 0.978723 (-3455 25);
FORCEPROP 1 LASTPIN (-3500 0) $PN 1
J 0
(-3495 -38);
DISPLAY 0.787234 (-3495 -38);
PAINT MONO (-3495 -38);
FORCEPROP 1 LASTPIN (-3500 -200) $PN 2
J 0
(-3495 -190);
DISPLAY 0.787234 (-3495 -190);
PAINT MONO (-3495 -190);
FORCEPROP 2 LAST CDS_LIB pure_quanta
J 0
(-3500 -100);
DISPLAY INVISIBLE (-3500 -100);
FORCEPROP 1 LAST PATH I8
J 0
(-3450 75);
DISPLAY 0.978723 (-3450 75);
PAINT WHITE (-3450 75);
DISPLAY INVISIBLE (-3450 75);
FORCEPROP 0 LAST CDS_LOCATION R4449
J 0
(-3450 75);
DISPLAY 1.021277 (-3450 75);
DISPLAY INVISIBLE (-3450 75);
FORCEPROP 0 LAST $SEC 1
J 0
(-3450 75);
DISPLAY 0.680851 (-3450 75);
PAINT MONO (-3450 75);
DISPLAY INVISIBLE (-3450 75);
FORCEPROP 0 LAST CDS_SEC 1
J 0
(-3450 75);
DISPLAY 1.021277 (-3450 75);
DISPLAY INVISIBLE (-3450 75);
FORCEADD UNIVERSAL_GND..1
(4125 1700);
FORCEPROP 3 LASTPIN (4125 1750) SIG_NAME GND\g
J 0
(4135 1760);
DISPLAY 0.659574 (4135 1760);
PAINT MONO (4135 1760);
DISPLAY INVISIBLE (4135 1760);
FORCEPROP 2 LAST CDS_LIB logical_power
J 0
(4125 1700);
DISPLAY INVISIBLE (4125 1700);
FORCEPROP 1 LAST HDL_POWER GND
J 1
(4150 1625);
DISPLAY 0.872340 (4150 1625);
PAINT GREEN (4150 1625);
DISPLAY INVISIBLE (4150 1625);
FORCEPROP 1 LAST PATH I80
J 0
(4200 1700);
DISPLAY 0.872340 (4200 1700);
PAINT AQUA (4200 1700);
DISPLAY INVISIBLE (4200 1700);
FORCEADD Q_CAP..1
(4125 1925);
FORCEPROP 1 LAST PART_NUMBER CH01206JB05
J 0
(4175 1775);
DISPLAY 0.638298 (4175 1775);
DISPLAY INVISIBLE (4175 1775);
FORCEPROP 1 LAST TOLERANCE 5%
J 0
(4175 1875);
DISPLAY 0.638298 (4175 1875);
FORCEPROP 1 LAST VALUE 12PF
J 0
(4175 1975);
DISPLAY 0.638298 (4175 1975);
FORCEPROP 1 LAST VOLTAGE 50V
J 0
(4175 1925);
DISPLAY 0.638298 (4175 1925);
FORCEPROP 1 LAST MATERIAL EMPTY
J 0
(4175 1825);
DISPLAY 0.638298 (4175 1825);
FORCEPROP 1 LAST PACK_TYPE C0402
J 0
(4175 1725);
DISPLAY 0.638298 (4175 1725);
FORCEPROP 1 LAST $LOCATION C2326
J 0
(4175 2025);
DISPLAY 0.638298 (4175 2025);
FORCEPROP 1 LASTPIN (4125 2025) $PN 1
J 0
(4135 2005);
DISPLAY 0.787234 (4135 2005);
PAINT MONO (4135 2005);
FORCEPROP 1 LASTPIN (4125 1825) $PN 2
J 0
(4135 1805);
DISPLAY 0.787234 (4135 1805);
PAINT MONO (4135 1805);
FORCEPROP 2 LAST CDS_LIB pure_quanta
J 0
(4125 1925);
DISPLAY INVISIBLE (4125 1925);
FORCEPROP 1 LAST PATH I81
J 0
(4175 2075);
DISPLAY 0.978723 (4175 2075);
PAINT WHITE (4175 2075);
DISPLAY INVISIBLE (4175 2075);
FORCEPROP 0 LAST CDS_LOCATION C2326
J 0
(4175 2075);
DISPLAY 1.021277 (4175 2075);
DISPLAY INVISIBLE (4175 2075);
FORCEPROP 0 LAST $SEC 1
J 0
(4175 2075);
DISPLAY 0.680851 (4175 2075);
PAINT MONO (4175 2075);
DISPLAY INVISIBLE (4175 2075);
FORCEPROP 0 LAST CDS_SEC 1
J 0
(4175 2075);
DISPLAY 1.021277 (4175 2075);
DISPLAY INVISIBLE (4175 2075);
FORCEADD UNIVERSAL_GND..1
(4350 1875);
FORCEPROP 3 LASTPIN (4350 1925) SIG_NAME GND\g
J 0
(4360 1935);
DISPLAY 0.659574 (4360 1935);
PAINT MONO (4360 1935);
DISPLAY INVISIBLE (4360 1935);
FORCEPROP 2 LAST CDS_LIB logical_power
J 0
(4350 1875);
DISPLAY INVISIBLE (4350 1875);
FORCEPROP 1 LAST HDL_POWER GND
J 1
(4375 1800);
DISPLAY 0.872340 (4375 1800);
PAINT GREEN (4375 1800);
DISPLAY INVISIBLE (4375 1800);
FORCEPROP 1 LAST PATH I82
J 0
(4425 1875);
DISPLAY 0.872340 (4425 1875);
PAINT AQUA (4425 1875);
DISPLAY INVISIBLE (4425 1875);
FORCEADD Q_XTAL_4P_13BI_24GND..1
(4675 2100);
FORCEPROP 1 LAST PART_NUMBER BG6120000E0
J 0
(4542 2375);
DISPLAY 0.723404 (4542 2375);
PAINT GREEN (4542 2375);
DISPLAY INVISIBLE (4542 2375);
FORCEPROP 1 LAST MATERIAL EMPTY
J 0
(4542 2279);
DISPLAY 0.723404 (4542 2279);
PAINT GREEN (4542 2279);
FORCEPROP 2 LAST VALUE 12MHZ
J 0
(4550 2500);
DISPLAY 1.021277 (4550 2500);
FORCEPROP 2 LAST PART_TYPE SMLF
J 0
(4550 2550);
DISPLAY 1.021277 (4550 2550);
FORCEPROP 1 LAST $LOCATION Y9
J 0
(4542 2466);
DISPLAY 0.723404 (4542 2466);
PAINT GREEN (4542 2466);
FORCEPROP 0 LASTPIN (4400 1975) $PN 2
J 2
(4390 1985);
DISPLAY 0.680851 (4390 1985);
PAINT MONO (4390 1985);
FORCEPROP 0 LASTPIN (4950 1975) $PN 4
J 0
(4960 1985);
DISPLAY 0.680851 (4960 1985);
PAINT MONO (4960 1985);
FORCEPROP 0 LASTPIN (4400 2175) $PN 1
J 2
(4390 2185);
DISPLAY 0.680851 (4390 2185);
PAINT MONO (4390 2185);
FORCEPROP 0 LASTPIN (4950 2175) $PN 3
J 0
(4960 2185);
DISPLAY 0.680851 (4960 2185);
PAINT MONO (4960 2185);
FORCEPROP 2 LAST CDS_LIB pure_quanta
J 0
(4675 2100);
DISPLAY INVISIBLE (4675 2100);
FORCEPROP 1 LAST PIN_NAMES_ROTATE True
J 0
(4675 2100);
DISPLAY 0.489362 (4675 2100);
PAINT GREEN (4675 2100);
DISPLAY INVISIBLE (4675 2100);
FORCEPROP 1 LAST CDS_LMAN_SYM_OUTLINE -125,175,125,-175
J 0
(4675 2100);
DISPLAY 0.468085 (4675 2100);
PAINT GREEN (4675 2100);
DISPLAY INVISIBLE (4675 2100);
FORCEPROP 1 LAST PATH I83
J 0
(4800 1925);
DISPLAY 0.723404 (4800 1925);
PAINT GREEN (4800 1925);
DISPLAY INVISIBLE (4800 1925);
FORCEPROP 0 LAST CDS_LOCATION Y9
J 0
(4550 2600);
DISPLAY 1.021277 (4550 2600);
DISPLAY INVISIBLE (4550 2600);
FORCEPROP 0 LAST $SEC 1
J 0
(4550 2600);
DISPLAY 0.680851 (4550 2600);
PAINT MONO (4550 2600);
DISPLAY INVISIBLE (4550 2600);
FORCEPROP 0 LAST CDS_SEC 1
J 0
(4550 2600);
DISPLAY 1.021277 (4550 2600);
DISPLAY INVISIBLE (4550 2600);
FORCEADD UNIVERSAL_GND..1
(5000 1875);
FORCEPROP 3 LASTPIN (5000 1925) SIG_NAME GND\g
J 0
(5010 1935);
DISPLAY 0.659574 (5010 1935);
PAINT MONO (5010 1935);
DISPLAY INVISIBLE (5010 1935);
FORCEPROP 2 LAST CDS_LIB logical_power
J 0
(5000 1875);
DISPLAY INVISIBLE (5000 1875);
FORCEPROP 1 LAST HDL_POWER GND
J 1
(5025 1800);
DISPLAY 0.872340 (5025 1800);
PAINT GREEN (5025 1800);
DISPLAY INVISIBLE (5025 1800);
FORCEPROP 1 LAST PATH I84
J 0
(5075 1875);
DISPLAY 0.872340 (5075 1875);
PAINT AQUA (5075 1875);
DISPLAY INVISIBLE (5075 1875);
FORCEADD Q_CAP..1
(5125 1925);
FORCEPROP 1 LAST PART_NUMBER CH01206JB05
J 0
(5175 1775);
DISPLAY 0.510638 (5175 1775);
DISPLAY INVISIBLE (5175 1775);
FORCEPROP 1 LAST PACK_TYPE C0402
J 0
(5175 1725);
DISPLAY 0.638298 (5175 1725);
FORCEPROP 1 LAST MATERIAL EMPTY
J 0
(5175 1825);
DISPLAY 0.638298 (5175 1825);
FORCEPROP 1 LAST TOLERANCE 5%
J 0
(5175 1875);
DISPLAY 0.638298 (5175 1875);
FORCEPROP 1 LAST VALUE 12PF
J 0
(5175 1975);
DISPLAY 0.638298 (5175 1975);
FORCEPROP 1 LAST VOLTAGE 50V
J 0
(5175 1925);
DISPLAY 0.638298 (5175 1925);
FORCEPROP 1 LAST $LOCATION C2327
J 0
(5175 2025);
DISPLAY 0.638298 (5175 2025);
FORCEPROP 1 LASTPIN (5125 2025) $PN 1
J 0
(5135 2005);
DISPLAY 0.787234 (5135 2005);
PAINT MONO (5135 2005);
FORCEPROP 1 LASTPIN (5125 1825) $PN 2
J 0
(5135 1805);
DISPLAY 0.787234 (5135 1805);
PAINT MONO (5135 1805);
FORCEPROP 2 LAST CDS_LIB pure_quanta
J 0
(5125 1925);
DISPLAY INVISIBLE (5125 1925);
FORCEPROP 1 LAST PATH I85
J 0
(5175 2075);
DISPLAY 0.978723 (5175 2075);
PAINT WHITE (5175 2075);
DISPLAY INVISIBLE (5175 2075);
FORCEPROP 0 LAST CDS_LOCATION C2327
J 0
(5175 2075);
DISPLAY 1.021277 (5175 2075);
DISPLAY INVISIBLE (5175 2075);
FORCEPROP 0 LAST $SEC 1
J 0
(5175 2075);
DISPLAY 0.680851 (5175 2075);
PAINT MONO (5175 2075);
DISPLAY INVISIBLE (5175 2075);
FORCEPROP 0 LAST CDS_SEC 1
J 0
(5175 2075);
DISPLAY 1.021277 (5175 2075);
DISPLAY INVISIBLE (5175 2075);
FORCEADD UNIVERSAL_GND..1
(5125 1700);
FORCEPROP 3 LASTPIN (5125 1750) SIG_NAME GND\g
J 0
(5135 1760);
DISPLAY 0.659574 (5135 1760);
PAINT MONO (5135 1760);
DISPLAY INVISIBLE (5135 1760);
FORCEPROP 2 LAST CDS_LIB logical_power
J 0
(5125 1700);
DISPLAY INVISIBLE (5125 1700);
FORCEPROP 1 LAST HDL_POWER GND
J 1
(5150 1625);
DISPLAY 0.872340 (5150 1625);
PAINT GREEN (5150 1625);
DISPLAY INVISIBLE (5150 1625);
FORCEPROP 1 LAST PATH I86
J 0
(5200 1700);
DISPLAY 0.872340 (5200 1700);
PAINT AQUA (5200 1700);
DISPLAY INVISIBLE (5200 1700);
FORCEADD OFFPAGE..5
R 2
(-175 -325);
FORCEPROP 2 LAST $XR0 196 
J 0
(14 -325);
DISPLAY 0.638298 (14 -325);
PAINT MONO (14 -325);
FORCEPROP 2 LAST CDS_LIB standard
J 0
(-175 -325);
DISPLAY INVISIBLE (-175 -325);
FORCEPROP 1 LAST OFFPAGE TRUE
J 2
(-500 -450);
DISPLAY 0.872340 (-500 -450);
PAINT GREEN (-500 -450);
DISPLAY INVISIBLE (-500 -450);
FORCEPROP 1 LAST COMMENT_BODY TRUE
J 2
(-275 -400);
DISPLAY 0.872340 (-275 -400);
PAINT GREEN (-275 -400);
DISPLAY INVISIBLE (-275 -400);
FORCEPROP 2 LAST PATH I87
J 0
(25 -275);
DISPLAY 1.021277 (25 -275);
DISPLAY INVISIBLE (25 -275);
FORCEADD Q_RES..2
(-1575 -1475);
FORCEPROP 1 LAST PART_NUMBER CS04992FB07
J 0
(-1535 -1600);
DISPLAY 0.510638 (-1535 -1600);
DISPLAY INVISIBLE (-1535 -1600);
FORCEPROP 1 LAST VALUE 49.9
J 0
(-1525 -1500);
DISPLAY 0.510638 (-1525 -1500);
FORCEPROP 1 LAST MATERIAL EMPTY
J 0
(-1535 -1550);
DISPLAY 0.510638 (-1535 -1550);
PAINT RED (-1535 -1550);
FORCEPROP 1 LAST $LOCATION R4487
J 0
(-1530 -1350);
DISPLAY 0.638298 (-1530 -1350);
FORCEPROP 1 LASTPIN (-1575 -1375) $PN 1
J 0
(-1570 -1413);
DISPLAY 0.787234 (-1570 -1413);
PAINT MONO (-1570 -1413);
FORCEPROP 1 LASTPIN (-1575 -1575) $PN 2
J 0
(-1570 -1565);
DISPLAY 0.787234 (-1570 -1565);
PAINT MONO (-1570 -1565);
FORCEPROP 1 LAST WATTAGE 1/16W
J 0
(-1535 -1500);
DISPLAY 0.510638 (-1535 -1500);
DISPLAY INVISIBLE (-1535 -1500);
FORCEPROP 1 LAST TOLERANCE 1%
J 0
(-1530 -1450);
DISPLAY 0.510638 (-1530 -1450);
DISPLAY INVISIBLE (-1530 -1450);
FORCEPROP 1 LAST PACK_TYPE 0402LF
J 0
(-1525 -1650);
DISPLAY 0.510638 (-1525 -1650);
DISPLAY INVISIBLE (-1525 -1650);
FORCEPROP 2 LAST CDS_LIB pure_quanta
J 0
(-1575 -1475);
DISPLAY INVISIBLE (-1575 -1475);
FORCEPROP 1 LAST PATH I88
J 0
(-1525 -1300);
DISPLAY 0.978723 (-1525 -1300);
PAINT WHITE (-1525 -1300);
DISPLAY INVISIBLE (-1525 -1300);
FORCEPROP 0 LAST CDS_LOCATION R4487
J 0
(-1525 -1300);
DISPLAY 1.021277 (-1525 -1300);
DISPLAY INVISIBLE (-1525 -1300);
FORCEPROP 0 LAST $SEC 1
J 0
(-1525 -1300);
DISPLAY 0.680851 (-1525 -1300);
PAINT MONO (-1525 -1300);
DISPLAY INVISIBLE (-1525 -1300);
FORCEPROP 0 LAST CDS_SEC 1
J 0
(-1525 -1300);
DISPLAY 1.021277 (-1525 -1300);
DISPLAY INVISIBLE (-1525 -1300);
FORCEADD UNIVERSAL_GND..1
(-1575 -1700);
FORCEPROP 3 LASTPIN (-1575 -1650) SIG_NAME GND\g
J 0
(-1565 -1640);
DISPLAY 0.659574 (-1565 -1640);
PAINT MONO (-1565 -1640);
DISPLAY INVISIBLE (-1565 -1640);
FORCEPROP 2 LAST CDS_LIB logical_power
J 0
(-1575 -1700);
DISPLAY INVISIBLE (-1575 -1700);
FORCEPROP 1 LAST HDL_POWER GND
J 1
(-1550 -1775);
DISPLAY 0.872340 (-1550 -1775);
PAINT GREEN (-1550 -1775);
DISPLAY INVISIBLE (-1550 -1775);
FORCEPROP 1 LAST PATH I89
J 0
(-1500 -1700);
DISPLAY 0.872340 (-1500 -1700);
PAINT AQUA (-1500 -1700);
DISPLAY INVISIBLE (-1500 -1700);
FORCEPROP 2 LAST ROOM IO_SLOT
J 1
(-1800 -1625);
DISPLAY 0.744681 (-1800 -1625);
DISPLAY INVISIBLE (-1800 -1625);
FORCEADD Q_RES..2
(-3500 500);
FORCEPROP 1 LAST PART_NUMBER CS31002FB08
J 0
(-3460 375);
DISPLAY 0.723404 (-3460 375);
PAINT WHITE (-3460 375);
DISPLAY INVISIBLE (-3460 375);
FORCEPROP 1 LAST PACK_TYPE 0402LF
J 0
(-3460 325);
DISPLAY 0.723404 (-3460 325);
PAINT SKYBLUE (-3460 325);
FORCEPROP 1 LAST VALUE 10K
J 0
(-3455 575);
DISPLAY 0.723404 (-3455 575);
PAINT SKYBLUE (-3455 575);
FORCEPROP 1 LAST TOLERANCE 1%
J 0
(-3455 525);
DISPLAY 0.723404 (-3455 525);
PAINT SKYBLUE (-3455 525);
FORCEPROP 1 LAST WATTAGE 1/16W
J 0
(-3460 475);
DISPLAY 0.723404 (-3460 475);
PAINT SKYBLUE (-3460 475);
FORCEPROP 1 LAST MATERIAL EMPTY
J 0
(-3460 425);
DISPLAY 0.723404 (-3460 425);
PAINT SKYBLUE (-3460 425);
FORCEPROP 1 LAST $LOCATION R4448
J 0
(-3455 625);
DISPLAY 0.978723 (-3455 625);
FORCEPROP 1 LASTPIN (-3500 600) $PN 1
J 0
(-3495 562);
DISPLAY 0.787234 (-3495 562);
PAINT MONO (-3495 562);
FORCEPROP 1 LASTPIN (-3500 400) $PN 2
J 0
(-3495 410);
DISPLAY 0.787234 (-3495 410);
PAINT MONO (-3495 410);
FORCEPROP 2 LAST CDS_LIB pure_quanta
J 0
(-3500 500);
DISPLAY INVISIBLE (-3500 500);
FORCEPROP 1 LAST PATH I9
J 0
(-3450 675);
DISPLAY 0.978723 (-3450 675);
PAINT WHITE (-3450 675);
DISPLAY INVISIBLE (-3450 675);
FORCEPROP 0 LAST CDS_LOCATION R4448
J 0
(-3450 675);
DISPLAY 1.021277 (-3450 675);
DISPLAY INVISIBLE (-3450 675);
FORCEPROP 0 LAST $SEC 1
J 0
(-3450 675);
DISPLAY 0.680851 (-3450 675);
PAINT MONO (-3450 675);
DISPLAY INVISIBLE (-3450 675);
FORCEPROP 0 LAST CDS_SEC 1
J 0
(-3450 675);
DISPLAY 1.021277 (-3450 675);
DISPLAY INVISIBLE (-3450 675);
FORCEADD Q_RES..2
(-1750 -1475);
FORCEPROP 1 LAST PART_NUMBER CS04992FB07
J 0
(-1710 -1600);
DISPLAY 0.510638 (-1710 -1600);
DISPLAY INVISIBLE (-1710 -1600);
FORCEPROP 1 LAST MATERIAL EMPTY
J 0
(-1710 -1550);
DISPLAY 0.510638 (-1710 -1550);
PAINT RED (-1710 -1550);
FORCEPROP 1 LAST VALUE 49.9
J 0
(-1700 -1500);
DISPLAY 0.510638 (-1700 -1500);
FORCEPROP 1 LAST $LOCATION R4486
J 0
(-1705 -1350);
DISPLAY 0.638298 (-1705 -1350);
FORCEPROP 1 LASTPIN (-1750 -1375) $PN 1
J 0
(-1745 -1413);
DISPLAY 0.787234 (-1745 -1413);
PAINT MONO (-1745 -1413);
FORCEPROP 1 LASTPIN (-1750 -1575) $PN 2
J 0
(-1745 -1565);
DISPLAY 0.787234 (-1745 -1565);
PAINT MONO (-1745 -1565);
FORCEPROP 1 LAST PACK_TYPE 0402LF
J 0
(-1700 -1650);
DISPLAY 0.510638 (-1700 -1650);
DISPLAY INVISIBLE (-1700 -1650);
FORCEPROP 1 LAST TOLERANCE 1%
J 0
(-1705 -1450);
DISPLAY 0.510638 (-1705 -1450);
DISPLAY INVISIBLE (-1705 -1450);
FORCEPROP 1 LAST WATTAGE 1/16W
J 0
(-1710 -1500);
DISPLAY 0.510638 (-1710 -1500);
DISPLAY INVISIBLE (-1710 -1500);
FORCEPROP 2 LAST CDS_LIB pure_quanta
J 0
(-1750 -1475);
DISPLAY INVISIBLE (-1750 -1475);
FORCEPROP 1 LAST PATH I90
J 0
(-1700 -1300);
DISPLAY 0.978723 (-1700 -1300);
PAINT WHITE (-1700 -1300);
DISPLAY INVISIBLE (-1700 -1300);
FORCEPROP 0 LAST CDS_LOCATION R4486
J 0
(-1700 -1300);
DISPLAY 1.021277 (-1700 -1300);
DISPLAY INVISIBLE (-1700 -1300);
FORCEPROP 0 LAST $SEC 1
J 0
(-1700 -1300);
DISPLAY 0.680851 (-1700 -1300);
PAINT MONO (-1700 -1300);
DISPLAY INVISIBLE (-1700 -1300);
FORCEPROP 0 LAST CDS_SEC 1
J 0
(-1700 -1300);
DISPLAY 1.021277 (-1700 -1300);
DISPLAY INVISIBLE (-1700 -1300);
FORCEADD UNIVERSAL_GND..1
(-1750 -1700);
FORCEPROP 3 LASTPIN (-1750 -1650) SIG_NAME GND\g
J 0
(-1740 -1640);
DISPLAY 0.659574 (-1740 -1640);
PAINT MONO (-1740 -1640);
DISPLAY INVISIBLE (-1740 -1640);
FORCEPROP 2 LAST CDS_LIB logical_power
J 0
(-1750 -1700);
DISPLAY INVISIBLE (-1750 -1700);
FORCEPROP 1 LAST HDL_POWER GND
J 1
(-1725 -1775);
DISPLAY 0.872340 (-1725 -1775);
PAINT GREEN (-1725 -1775);
DISPLAY INVISIBLE (-1725 -1775);
FORCEPROP 1 LAST PATH I91
J 0
(-1675 -1700);
DISPLAY 0.872340 (-1675 -1700);
PAINT AQUA (-1675 -1700);
DISPLAY INVISIBLE (-1675 -1700);
FORCEPROP 2 LAST ROOM IO_SLOT
J 1
(-1975 -1625);
DISPLAY 0.744681 (-1975 -1625);
DISPLAY INVISIBLE (-1975 -1625);
FORCEADD QUANTA_TITLE_BLOCK_C..1
(5500 -3550);
FORCEPROP 0 LAST CDS_CON_LAST_MODIFIED Fri Aug 25 14:03:10 2023
J 0
(3615 -3535);
DISPLAY INVISIBLE (3615 -3535);
FORCEPROP 1 LAST CUSTOM_TXT_CDS <CON_LAST_MODIFIED>
J 0
(3615 -3535);
DISPLAY 0.978723 (3615 -3535);
FORCEPROP 2 LAST CUSTOM_TXT_CDS <XR_PAGE_TITLE>
J 0
(-2390 1700);
DISPLAY 0.638298 (-2390 1700);
PAINT PINK (-2390 1700);
DISPLAY INVISIBLE (-2390 1700);
FORCEPROP 1 LAST CUSTOM_TXT_CDS <NAME_2>
J 0
(2325 -3500);
FORCEPROP 1 LAST CUSTOM_TXT_CDS <NAME_1>
J 0
(2325 -3375);
FORCEPROP 1 LAST CUSTOM_TXT_CDS <Q_NUMBER>
J 0
(4097 -3447);
DISPLAY 1.212766 (4097 -3447);
FORCEPROP 1 LAST CUSTOM_TXT_CDS <Q_PROJ>
J 0
(3118 -3448);
DISPLAY 1.212766 (3118 -3448);
FORCEPROP 1 LAST CUSTOM_TXT_CDS <Q_REV>
J 0
(5316 -3447);
DISPLAY 1.212766 (5316 -3447);
FORCEPROP 1 LAST CUSTOM_TXT_CDS <CON_PAGE_NUM> OF <CON_TOTAL_PAGES>
J 0
(5054 -3532);
DISPLAY 0.978723 (5054 -3532);
FORCEPROP 1 LAST Q_TITLE PCH - USB EXT HUB
J 0
(-3866 -3524);
DISPLAY 2.446809 (-3866 -3524);
PAINT GREEN (-3866 -3524);
FORCEPROP 1 LAST Q_DEPT 
J 1
(1737 -3501);
DISPLAY 1.957447 (1737 -3501);
PAINT GREEN (1737 -3501);
FORCEPROP 2 LAST CDS_XR_PAGE_TITLE CR-196 : @S9S_MB_2U_LIB.S9S_MB_2U(SCH_1):PAGE196
J 0
(-2390 1700);
DISPLAY 0.638298 (-2390 1700);
PAINT PINK (-2390 1700);
DISPLAY INVISIBLE (-2390 1700);
FORCEPROP 1 LAST COMMENT_BODY TRUE
J 0
(5512 -3563);
DISPLAY 0.978723 (5512 -3563);
PAINT GREEN (5512 -3563);
DISPLAY INVISIBLE (5512 -3563);
FORCEPROP 2 LAST PAGE_BORDER TRUE
J 0
(-2390 1700);
DISPLAY 0.638298 (-2390 1700);
PAINT PINK (-2390 1700);
DISPLAY INVISIBLE (-2390 1700);
FORCEPROP 1 LAST CDS_LMAN_SYM_OUTLINE -9475,6775,100,-125
J 0
(5500 -3550);
DISPLAY 0.468085 (5500 -3550);
PAINT GREEN (5500 -3550);
DISPLAY INVISIBLE (5500 -3550);
FORCEPROP 2 LAST CDS_LIB pure_quanta
J 0
(5500 -3550);
DISPLAY INVISIBLE (5500 -3550);
FORCEADD DNS..1
R 1
(-1525 -2275);
PAINT RED (-1525 -2275);
FORCEPROP 2 LAST CDS_LIB mstr_misc
J 0
(-1525 -2275);
DISPLAY INVISIBLE (-1525 -2275);
FORCEPROP 1 LAST COMMENT_BODY TRUE
R 2
J 0
(-1300 -2200);
DISPLAY 0.872340 (-1300 -2200);
PAINT GREEN (-1300 -2200);
DISPLAY INVISIBLE (-1300 -2200);
FORCEADD DNS..2
(-1575 -1500);
PAINT RED (-1575 -1500);
FORCEPROP 2 LAST CDS_LIB mstr_misc
J 0
(-1575 -1500);
DISPLAY INVISIBLE (-1575 -1500);
FORCEPROP 1 LAST COMMENT_BODY TRUE
R 1
J 0
(-1500 -1725);
DISPLAY 0.872340 (-1500 -1725);
PAINT GREEN (-1500 -1725);
DISPLAY INVISIBLE (-1500 -1725);
FORCEADD DNS..2
(-1750 -1500);
PAINT RED (-1750 -1500);
FORCEPROP 2 LAST CDS_LIB mstr_misc
J 0
(-1750 -1500);
DISPLAY INVISIBLE (-1750 -1500);
FORCEPROP 1 LAST COMMENT_BODY TRUE
R 1
J 0
(-1675 -1725);
DISPLAY 0.872340 (-1675 -1725);
PAINT GREEN (-1675 -1725);
DISPLAY INVISIBLE (-1675 -1725);
FORCEADD CAD_NOTE..1
(-1050 -1550);
FORCEPROP 0 LAST S1 R4454/R4460,R4455/R4461 CO-LAYOUT
J 0
(-1175 -1675);
DISPLAY 0.808511 (-1175 -1675);
PAINT WHITE (-1175 -1675);
FORCEPROP 2 LAST CDS_LIB logical_power
J 0
(-1050 -1550);
DISPLAY INVISIBLE (-1050 -1550);
FORCEPROP 1 LAST COMMENT_BODY TRUE
J 0
(-1025 -1450);
DISPLAY 0.978723 (-1025 -1450);
DISPLAY INVISIBLE (-1025 -1450);
FORCEADD DNS..1
R 1
(-500 -2700);
PAINT RED (-500 -2700);
FORCEPROP 2 LAST CDS_LIB mstr_misc
J 0
(-500 -2700);
DISPLAY INVISIBLE (-500 -2700);
FORCEPROP 1 LAST COMMENT_BODY TRUE
R 2
J 0
(-275 -2625);
DISPLAY 0.872340 (-275 -2625);
PAINT GREEN (-275 -2625);
DISPLAY INVISIBLE (-275 -2625);
FORCEADD DNS..1
R 1
(-25 -2725);
PAINT RED (-25 -2725);
FORCEPROP 2 LAST CDS_LIB mstr_misc
J 0
(-25 -2725);
DISPLAY INVISIBLE (-25 -2725);
FORCEPROP 1 LAST COMMENT_BODY TRUE
R 2
J 0
(200 -2650);
DISPLAY 0.872340 (200 -2650);
PAINT GREEN (200 -2650);
DISPLAY INVISIBLE (200 -2650);
FORCEADD DNS..1
(-3475 -100);
PAINT RED (-3475 -100);
FORCEPROP 2 LAST CDS_LIB mstr_misc
J 0
(-3475 -100);
DISPLAY INVISIBLE (-3475 -100);
FORCEPROP 1 LAST COMMENT_BODY TRUE
R 1
J 0
(-3400 -325);
DISPLAY 0.872340 (-3400 -325);
PAINT GREEN (-3400 -325);
DISPLAY INVISIBLE (-3400 -325);
FORCEADD DNS..1
(-875 -575);
PAINT RED (-875 -575);
FORCEPROP 2 LAST CDS_LIB mstr_misc
J 0
(-875 -575);
DISPLAY INVISIBLE (-875 -575);
FORCEPROP 1 LAST COMMENT_BODY TRUE
R 1
J 0
(-800 -800);
DISPLAY 0.872340 (-800 -800);
PAINT GREEN (-800 -800);
DISPLAY INVISIBLE (-800 -800);
FORCEADD DNS..1
R 1
(525 -2375);
PAINT RED (525 -2375);
FORCEPROP 2 LAST CDS_LIB mstr_misc
J 0
(525 -2375);
DISPLAY INVISIBLE (525 -2375);
FORCEPROP 1 LAST COMMENT_BODY TRUE
R 2
J 0
(750 -2300);
DISPLAY 0.872340 (750 -2300);
PAINT GREEN (750 -2300);
DISPLAY INVISIBLE (750 -2300);
FORCEADD DNS..1
(-875 -450);
PAINT RED (-875 -450);
FORCEPROP 2 LAST CDS_LIB mstr_misc
J 0
(-875 -450);
DISPLAY INVISIBLE (-875 -450);
FORCEPROP 1 LAST COMMENT_BODY TRUE
R 1
J 0
(-800 -675);
DISPLAY 0.872340 (-800 -675);
PAINT GREEN (-800 -675);
DISPLAY INVISIBLE (-800 -675);
FORCEADD DNS..1
(-875 -325);
PAINT RED (-875 -325);
FORCEPROP 2 LAST CDS_LIB mstr_misc
J 0
(-875 -325);
DISPLAY INVISIBLE (-875 -325);
FORCEPROP 1 LAST COMMENT_BODY TRUE
R 1
J 0
(-800 -550);
DISPLAY 0.872340 (-800 -550);
PAINT GREEN (-800 -550);
DISPLAY INVISIBLE (-800 -550);
FORCEADD DNS..1
(-875 -175);
PAINT RED (-875 -175);
FORCEPROP 2 LAST CDS_LIB mstr_misc
J 0
(-875 -175);
DISPLAY INVISIBLE (-875 -175);
FORCEPROP 1 LAST COMMENT_BODY TRUE
R 1
J 0
(-800 -400);
DISPLAY 0.872340 (-800 -400);
PAINT GREEN (-800 -400);
DISPLAY INVISIBLE (-800 -400);
FORCEADD DNS..1
(-1250 625);
PAINT RED (-1250 625);
FORCEPROP 2 LAST CDS_LIB mstr_misc
J 0
(-1250 625);
DISPLAY INVISIBLE (-1250 625);
FORCEPROP 1 LAST COMMENT_BODY TRUE
R 1
J 0
(-1175 400);
DISPLAY 0.872340 (-1175 400);
PAINT GREEN (-1175 400);
DISPLAY INVISIBLE (-1175 400);
FORCEADD DNS..1
R 1
(2150 -2650);
PAINT RED (2150 -2650);
FORCEPROP 2 LAST CDS_LIB mstr_misc
J 0
(2150 -2650);
DISPLAY INVISIBLE (2150 -2650);
FORCEPROP 1 LAST COMMENT_BODY TRUE
R 2
J 0
(2375 -2575);
DISPLAY 0.872340 (2375 -2575);
PAINT GREEN (2375 -2575);
DISPLAY INVISIBLE (2375 -2575);
FORCEADD CAD_NOTE..1
(2200 -1975);
FORCEPROP 0 LAST S1 SHORT THE NET USB2_HUB_2_EXT_R_DP/DN TO USB2_HUB_2_BUF_EXT_R_DP/DN
J 0
(2075 -2100);
DISPLAY 0.808511 (2075 -2100);
PAINT WHITE (2075 -2100);
FORCEPROP 2 LAST CDS_LIB logical_power
J 0
(2200 -1975);
DISPLAY INVISIBLE (2200 -1975);
FORCEPROP 1 LAST COMMENT_BODY TRUE
J 0
(2225 -1875);
DISPLAY 0.978723 (2225 -1875);
DISPLAY INVISIBLE (2225 -1875);
FORCEADD DNS..2
(3225 1450);
PAINT RED (3225 1450);
FORCEPROP 2 LAST CDS_LIB mstr_misc
J 0
(3225 1450);
DISPLAY INVISIBLE (3225 1450);
FORCEPROP 1 LAST COMMENT_BODY TRUE
R 1
J 0
(3300 1225);
DISPLAY 0.872340 (3300 1225);
PAINT GREEN (3300 1225);
DISPLAY INVISIBLE (3300 1225);
FORCEADD CAD_NOTE..1
(4075 1150);
FORCEPROP 0 LAST S1 R4471/R4473,R4472/R4474 CO-LAYOUT
J 0
(3950 1025);
DISPLAY 0.808511 (3950 1025);
PAINT WHITE (3950 1025);
FORCEPROP 2 LAST CDS_LIB logical_power
J 0
(4075 1150);
DISPLAY INVISIBLE (4075 1150);
FORCEPROP 1 LAST COMMENT_BODY TRUE
J 0
(4100 1250);
DISPLAY 0.978723 (4100 1250);
DISPLAY INVISIBLE (4100 1250);
FORCEADD DNS..2
(775 1675);
PAINT RED (775 1675);
FORCEPROP 2 LAST CDS_LIB mstr_misc
J 0
(775 1675);
DISPLAY INVISIBLE (775 1675);
FORCEPROP 1 LAST COMMENT_BODY TRUE
R 1
J 0
(850 1450);
DISPLAY 0.872340 (850 1450);
PAINT GREEN (850 1450);
DISPLAY INVISIBLE (850 1450);
FORCEADD DNS..2
(4675 2200);
PAINT RED (4675 2200);
FORCEPROP 2 LAST CDS_LIB mstr_misc
J 0
(4675 2200);
DISPLAY INVISIBLE (4675 2200);
FORCEPROP 1 LAST COMMENT_BODY TRUE
R 1
J 0
(4750 1975);
DISPLAY 0.872340 (4750 1975);
PAINT GREEN (4750 1975);
DISPLAY INVISIBLE (4750 1975);
FORCEADD DNS..2
(5150 1925);
PAINT RED (5150 1925);
FORCEPROP 2 LAST CDS_LIB mstr_misc
J 0
(5150 1925);
DISPLAY INVISIBLE (5150 1925);
FORCEPROP 1 LAST COMMENT_BODY TRUE
R 1
J 0
(5225 1700);
DISPLAY 0.872340 (5225 1700);
PAINT GREEN (5225 1700);
DISPLAY INVISIBLE (5225 1700);
FORCEADD DNS..2
(4150 1925);
PAINT RED (4150 1925);
FORCEPROP 2 LAST CDS_LIB mstr_misc
J 0
(4150 1925);
DISPLAY INVISIBLE (4150 1925);
FORCEPROP 1 LAST COMMENT_BODY TRUE
R 1
J 0
(4225 1700);
DISPLAY 0.872340 (4225 1700);
PAINT GREEN (4225 1700);
DISPLAY INVISIBLE (4225 1700);
FORCEADD DNS..2
(2150 1825);
PAINT RED (2150 1825);
FORCEPROP 2 LAST CDS_LIB mstr_misc
J 0
(2150 1825);
DISPLAY INVISIBLE (2150 1825);
FORCEPROP 1 LAST COMMENT_BODY TRUE
R 1
J 0
(2225 1600);
DISPLAY 0.872340 (2225 1600);
PAINT GREEN (2225 1600);
DISPLAY INVISIBLE (2225 1600);
FORCEADD DNS..2
(-425 1475);
PAINT RED (-425 1475);
FORCEPROP 2 LAST CDS_LIB mstr_misc
J 0
(-425 1475);
DISPLAY INVISIBLE (-425 1475);
FORCEPROP 1 LAST COMMENT_BODY TRUE
R 1
J 0
(-350 1250);
DISPLAY 0.872340 (-350 1250);
PAINT GREEN (-350 1250);
DISPLAY INVISIBLE (-350 1250);
FORCEADD DNS..2
(-3075 2350);
PAINT RED (-3075 2350);
FORCEPROP 2 LAST CDS_LIB mstr_misc
J 0
(-3075 2350);
DISPLAY INVISIBLE (-3075 2350);
FORCEPROP 1 LAST COMMENT_BODY TRUE
R 1
J 0
(-3000 2125);
DISPLAY 0.872340 (-3000 2125);
PAINT GREEN (-3000 2125);
DISPLAY INVISIBLE (-3000 2125);
FORCEADD DNS..2
(-2400 2050);
PAINT RED (-2400 2050);
FORCEPROP 2 LAST CDS_LIB mstr_misc
J 0
(-2400 2050);
DISPLAY INVISIBLE (-2400 2050);
FORCEPROP 1 LAST COMMENT_BODY TRUE
R 1
J 0
(-2325 1825);
DISPLAY 0.872340 (-2325 1825);
PAINT GREEN (-2325 1825);
DISPLAY INVISIBLE (-2325 1825);
FORCEADD DNS..2
(-1625 2050);
PAINT RED (-1625 2050);
FORCEPROP 2 LAST CDS_LIB mstr_misc
J 0
(-1625 2050);
DISPLAY INVISIBLE (-1625 2050);
FORCEPROP 1 LAST COMMENT_BODY TRUE
R 1
J 0
(-1550 1825);
DISPLAY 0.872340 (-1550 1825);
PAINT GREEN (-1550 1825);
DISPLAY INVISIBLE (-1550 1825);
FORCEADD DNS..2
(-1250 2050);
PAINT RED (-1250 2050);
FORCEPROP 2 LAST CDS_LIB mstr_misc
J 0
(-1250 2050);
DISPLAY INVISIBLE (-1250 2050);
FORCEPROP 1 LAST COMMENT_BODY TRUE
R 1
J 0
(-1175 1825);
DISPLAY 0.872340 (-1175 1825);
PAINT GREEN (-1175 1825);
DISPLAY INVISIBLE (-1175 1825);
FORCEADD DNS..2
(-875 2050);
PAINT RED (-875 2050);
FORCEPROP 2 LAST CDS_LIB mstr_misc
J 0
(-875 2050);
DISPLAY INVISIBLE (-875 2050);
FORCEPROP 1 LAST COMMENT_BODY TRUE
R 1
J 0
(-800 1825);
DISPLAY 0.872340 (-800 1825);
PAINT GREEN (-800 1825);
DISPLAY INVISIBLE (-800 1825);
FORCEADD DNS..2
(-500 2050);
PAINT RED (-500 2050);
FORCEPROP 2 LAST CDS_LIB mstr_misc
J 0
(-500 2050);
DISPLAY INVISIBLE (-500 2050);
FORCEPROP 1 LAST COMMENT_BODY TRUE
R 1
J 0
(-425 1825);
DISPLAY 0.872340 (-425 1825);
PAINT GREEN (-425 1825);
DISPLAY INVISIBLE (-425 1825);
FORCEADD DNS..2
(-150 2050);
PAINT RED (-150 2050);
FORCEPROP 2 LAST CDS_LIB mstr_misc
J 0
(-150 2050);
DISPLAY INVISIBLE (-150 2050);
FORCEPROP 1 LAST COMMENT_BODY TRUE
R 1
J 0
(-75 1825);
DISPLAY 0.872340 (-75 1825);
PAINT GREEN (-75 1825);
DISPLAY INVISIBLE (-75 1825);
FORCEADD DNS..2
(-2775 2050);
PAINT RED (-2775 2050);
FORCEPROP 2 LAST CDS_LIB mstr_misc
J 0
(-2775 2050);
DISPLAY INVISIBLE (-2775 2050);
FORCEPROP 1 LAST COMMENT_BODY TRUE
R 1
J 0
(-2700 1825);
DISPLAY 0.872340 (-2700 1825);
PAINT GREEN (-2700 1825);
DISPLAY INVISIBLE (-2700 1825);
FORCEADD DNS..2
(-2000 2050);
PAINT RED (-2000 2050);
FORCEPROP 2 LAST CDS_LIB mstr_misc
J 0
(-2000 2050);
DISPLAY INVISIBLE (-2000 2050);
FORCEPROP 1 LAST COMMENT_BODY TRUE
R 1
J 0
(-1925 1825);
DISPLAY 0.872340 (-1925 1825);
PAINT GREEN (-1925 1825);
DISPLAY INVISIBLE (-1925 1825);
FORCEADD DNS..2
(-2050 975);
PAINT RED (-2050 975);
FORCEPROP 2 LAST CDS_LIB mstr_misc
J 0
(-2050 975);
DISPLAY INVISIBLE (-2050 975);
FORCEPROP 1 LAST COMMENT_BODY TRUE
R 1
J 0
(-1975 750);
DISPLAY 0.872340 (-1975 750);
PAINT GREEN (-1975 750);
DISPLAY INVISIBLE (-1975 750);
FORCEADD DNS..2
(-3500 475);
PAINT RED (-3500 475);
FORCEPROP 2 LAST CDS_LIB mstr_misc
J 0
(-3500 475);
DISPLAY INVISIBLE (-3500 475);
FORCEPROP 1 LAST COMMENT_BODY TRUE
R 1
J 0
(-3425 250);
DISPLAY 0.872340 (-3425 250);
PAINT GREEN (-3425 250);
DISPLAY INVISIBLE (-3425 250);
FORCEADD DNS..2
(-1625 675);
PAINT RED (-1625 675);
FORCEPROP 2 LAST CDS_LIB mstr_misc
J 0
(-1625 675);
DISPLAY INVISIBLE (-1625 675);
FORCEPROP 1 LAST COMMENT_BODY TRUE
R 1
J 0
(-1550 450);
DISPLAY 0.872340 (-1550 450);
PAINT GREEN (-1550 450);
DISPLAY INVISIBLE (-1550 450);
FORCEADD DNS..2
(-425 625);
PAINT RED (-425 625);
FORCEPROP 2 LAST CDS_LIB mstr_misc
J 0
(-425 625);
DISPLAY INVISIBLE (-425 625);
FORCEPROP 1 LAST COMMENT_BODY TRUE
R 1
J 0
(-350 400);
DISPLAY 0.872340 (-350 400);
PAINT GREEN (-350 400);
DISPLAY INVISIBLE (-350 400);
FORCEADD DNS..2
(-100 600);
PAINT RED (-100 600);
FORCEPROP 2 LAST CDS_LIB mstr_misc
J 0
(-100 600);
DISPLAY INVISIBLE (-100 600);
FORCEPROP 1 LAST COMMENT_BODY TRUE
R 1
J 0
(-25 375);
DISPLAY 0.872340 (-25 375);
PAINT GREEN (-25 375);
DISPLAY INVISIBLE (-25 375);
FORCEADD DNS..2
(-1225 1300);
PAINT RED (-1225 1300);
FORCEPROP 2 LAST CDS_LIB mstr_misc
J 0
(-1225 1300);
DISPLAY INVISIBLE (-1225 1300);
FORCEPROP 1 LAST COMMENT_BODY TRUE
R 1
J 0
(-1150 1075);
DISPLAY 0.872340 (-1150 1075);
PAINT GREEN (-1150 1075);
DISPLAY INVISIBLE (-1150 1075);
FORCEADD DNS..1
R 1
(1400 -1725);
PAINT RED (1400 -1725);
FORCEPROP 2 LAST CDS_LIB mstr_misc
J 0
(1400 -1725);
DISPLAY INVISIBLE (1400 -1725);
FORCEPROP 1 LAST COMMENT_BODY TRUE
R 2
J 0
(1625 -1650);
DISPLAY 0.872340 (1625 -1650);
PAINT GREEN (1625 -1650);
DISPLAY INVISIBLE (1625 -1650);
FORCEADD DNS..1
R 1
(950 -1725);
PAINT RED (950 -1725);
FORCEPROP 2 LAST CDS_LIB mstr_misc
J 0
(950 -1725);
DISPLAY INVISIBLE (950 -1725);
FORCEPROP 1 LAST COMMENT_BODY TRUE
R 2
J 0
(1175 -1650);
DISPLAY 0.872340 (1175 -1650);
PAINT GREEN (1175 -1650);
DISPLAY INVISIBLE (1175 -1650);
WIRE 16 -1 (-3500 975)(-3500 600);
WIRE 16 -1 (-1250 1575)(-1250 1425);
WIRE 16 -1 (-1525 25)(-1525 -175);
WIRE 16 -1 (-3350 2450)(-3350 2350);
WIRE 16 -1 (1800 -1450)(1800 -1550);
WIRE 16 -1 (-1575 -1650)(-1575 -1575);
WIRE 16 -1 (-1750 -1650)(-1750 -1575);
WIRE 16 -1 (-500 -2775)(-500 -2850);
WIRE 16 -1 (-25 -2800)(-25 -2850);
WIRE 16 -1 (-3500 -475)(-3500 -200);
WIRE 16 -1 (-1625 475)(-1625 450);
WIRE 16 -1 (-1250 475)(-1625 475);
WIRE 16 -1 (-1625 600)(-1625 475);
WIRE 16 -1 (-100 525)(-100 400);
WIRE 16 -1 (-425 550)(-425 425);
WIRE 16 -1 (-2800 1775)(-2800 1700);
WIRE 16 -1 (-2800 1775)(-2425 1775);
WIRE 16 -1 (-2800 1950)(-2800 1775);
WIRE 16 -1 (2125 -2750)(2125 -2825);
WIRE 16 -1 (2025 -2550)(2025 -2425);
WIRE 16 -1 (1375 875)(1375 725);
WIRE 16 -1 (1250 875)(1375 875);
WIRE 16 -1 (2225 1825)(2625 1825);
WIRE 16 -1 (4125 1825)(4125 1750);
WIRE 16 -1 (4350 1975)(4350 1925);
WIRE 16 -1 (4400 1975)(4350 1975);
WIRE 16 -1 (5000 1975)(5000 1925);
WIRE 16 -1 (4950 1975)(5000 1975);
WIRE 16 -1 (5125 1825)(5125 1750);
WIRE 16 -1 (1375 -1950)(1375 -2025);
WIRE 16 -1 (925 -1950)(1375 -1950);
WIRE 16 -1 (1375 -1825)(1375 -1950);
WIRE 16 2175 (-1775 -2350)(-900 -2350);
WIRE 16 2175 (-900 -1800)(-900 -2350);
WIRE 16 2175 (-1775 -1800)(-1775 -2350);
WIRE 16 2175 (-1775 -1800)(-900 -1800);
WIRE 16 -1 (-1575 -1375)(-1575 -1275);
WIRE 16 -1 (-1575 -1275)(-1275 -1275);
WIRE 16 -1 (-1275 -1275)(-1275 -2000);
WIRE 16 -1 (-1275 -1125)(-1275 -1275);
WIRE 16 -1 (3475 -1125)(-1275 -1125);
FORCEPROP 2 LAST SIG_NAME USB2_HOST_PCH_0_DN
J 0
(515 -1115);
DISPLAY 0.808511 (515 -1115);
PAINT WHITE (515 -1115);
WIRE 16 -1 (3475 1100)(3475 -1125);
WIRE 16 -1 (-1275 -2275)(-1450 -2275);
WIRE 16 -1 (-1275 -2200)(-1275 -2275);
WIRE 16 -1 (150 -2275)(-1275 -2275);
FORCEPROP 2 LAST SIG_NAME USB2_HUB_2_BUF_EXT_R_DN
J 0
(-779 -2275);
DISPLAY 0.808511 (-779 -2275);
PAINT WHITE (-779 -2275);
FORCEPROP 2 LASTPROP $XR0 196 
J 0
(-1049 -2275);
DISPLAY 0.638298 (-1049 -2275);
PAINT MONO (-1049 -2275);
WIRE 16 -1 (-1350 -2225)(-1450 -2225);
WIRE 16 -1 (-1350 -2200)(-1350 -2225);
WIRE 16 -1 (150 -2225)(-1350 -2225);
FORCEPROP 2 LAST SIG_NAME USB2_HUB_2_BUF_EXT_R_DP
J 0
(-779 -2225);
DISPLAY 0.808511 (-779 -2225);
PAINT WHITE (-779 -2225);
FORCEPROP 2 LASTPROP $XR0 196 
J 0
(-1049 -2225);
DISPLAY 0.638298 (-1049 -2225);
PAINT MONO (-1049 -2225);
WIRE 16 -1 (-1750 -1375)(-1750 -1225);
WIRE 16 -1 (-1750 -1225)(-1350 -1225);
WIRE 16 -1 (-1350 -1225)(-1350 -2000);
WIRE 16 -1 (-1350 -1025)(-1350 -1225);
WIRE 16 -1 (3375 -1025)(-1350 -1025);
FORCEPROP 2 LAST SIG_NAME USB2_HOST_PCH_0_DP
J 0
(515 -1015);
DISPLAY 0.808511 (515 -1015);
PAINT WHITE (515 -1015);
WIRE 16 -1 (3375 1100)(3375 -1025);
WIRE 16 -1 (-2850 -2225)(-1650 -2225);
FORCEPROP 2 LAST SIG_NAME USB2_HUB_2_EXT_DP
J 0
(-2835 -2215);
DISPLAY 0.723404 (-2835 -2215);
PAINT WHITE (-2835 -2215);
WIRE 16 -1 (-3500 0)(-3500 175);
WIRE 16 -1 (-2425 175)(-3500 175);
FORCEPROP 2 LAST SIG_NAME USB_HUB_2_PSELF
J 0
(-3160 185);
DISPLAY 0.808511 (-3160 185);
PAINT WHITE (-3160 185);
WIRE 16 -1 (-3500 400)(-3500 175);
WIRE 16 -1 (1800 -2325)(900 -2325);
WIRE 16 -1 (1800 -1550)(1800 -2325);
WIRE 16 -1 (1375 -1625)(1375 -1550);
WIRE 16 -1 (1375 -1550)(1800 -1550);
WIRE 16 -1 (925 -1550)(925 -1625);
WIRE 16 -1 (925 -1550)(1375 -1550);
WIRE 16 -1 (925 -1825)(925 -1950);
WIRE 16 -1 (900 -2375)(2125 -2375);
FORCEPROP 2 LAST SIG_NAME PD_USB_HUB_2_VREG
J 0
(1015 -2365);
DISPLAY 0.723404 (1015 -2365);
PAINT WHITE (1015 -2365);
WIRE 16 -1 (2125 -2375)(2125 -2550);
WIRE 16 -1 (-500 -2425)(-500 -2575);
WIRE 16 -1 (150 -2425)(-500 -2425);
FORCEPROP 2 LAST SIG_NAME PD_USB_HUB_2_RSTN
J 0
(-485 -2415);
DISPLAY 0.723404 (-485 -2415);
PAINT WHITE (-485 -2415);
WIRE 16 -1 (-1250 550)(-1250 475);
WIRE 16 -1 (-1625 800)(-1625 925);
WIRE 16 -1 (-1625 925)(-1250 925);
WIRE 16 -1 (-1250 925)(-1250 750);
WIRE 16 -1 (-1250 925)(-1250 975);
WIRE 16 -1 (-1250 975)(-1250 1225);
WIRE 16 -1 (300 975)(-1250 975);
WIRE 16 -1 (-1975 975)(-1250 975);
FORCEPROP 2 LAST SIG_NAME RST_USB_HUB_2_R_N
J 0
(-1835 985);
DISPLAY 0.723404 (-1835 985);
PAINT WHITE (-1835 985);
WIRE 16 -1 (-2175 975)(-2825 975);
FORCEPROP 2 LAST SIG_NAME RST_USB_HUB_N
J 0
(-2810 985);
DISPLAY 0.723404 (-2810 985);
PAINT WHITE (-2810 985);
WIRE 16 -1 (-425 1025)(-425 750);
WIRE 16 -1 (300 1025)(-425 1025);
FORCEPROP 2 LAST SIG_NAME USB_HUB_2_RREF
J 0
(-260 1035);
DISPLAY 0.808511 (-260 1035);
PAINT WHITE (-260 1035);
WIRE 16 -1 (1250 1175)(1975 1175);
FORCEPROP 0 LAST SIG_NAME NC_USB_HUB_2_DP3
J 0
(1390 1185);
DISPLAY 0.723404 (1390 1185);
PAINT WHITE (1390 1185);
WIRE 16 -1 (1250 1225)(1975 1225);
FORCEPROP 0 LAST SIG_NAME NC_USB_HUB_2_DM2
J 0
(1390 1235);
DISPLAY 0.723404 (1390 1235);
PAINT WHITE (1390 1235);
WIRE 16 -1 (1250 1275)(1975 1275);
FORCEPROP 0 LAST SIG_NAME NC_USB_HUB_2_DP2
J 0
(1390 1285);
DISPLAY 0.723404 (1390 1285);
PAINT WHITE (1390 1285);
WIRE 16 -1 (2275 1325)(1250 1325);
FORCEPROP 2 LAST SIG_NAME USB2_HUB_2_EXT_DN
J 0
(1390 1335);
DISPLAY 0.723404 (1390 1335);
PAINT WHITE (1390 1335);
WIRE 16 2175 (3075 925)(3825 925);
WIRE 16 2175 (3825 1550)(3825 925);
WIRE 16 2175 (3075 1550)(3075 925);
WIRE 16 2175 (3075 1550)(3825 1550);
WIRE 16 -1 (5125 2175)(5125 2025);
WIRE 16 -1 (4950 2175)(5125 2175);
WIRE 16 -1 (5450 2175)(5125 2175);
WIRE 16 -1 (5450 1625)(5450 2175);
WIRE 16 -1 (1250 1625)(5450 1625);
FORCEPROP 2 LAST SIG_NAME USB_HUB_2_XTAL_OUT
J 0
(1390 1635);
DISPLAY 0.638298 (1390 1635);
PAINT WHITE (1390 1635);
WIRE 16 -1 (4125 2175)(4125 2025);
WIRE 16 -1 (4400 2175)(4125 2175);
WIRE 16 -1 (4125 2175)(4050 2175);
WIRE 16 -1 (4050 2175)(4050 1675);
WIRE 16 -1 (1250 1675)(4050 1675);
FORCEPROP 2 LAST SIG_NAME USB_HUB_2_XTAL_IN
J 0
(1390 1685);
DISPLAY 0.638298 (1390 1685);
PAINT WHITE (1390 1685);
WIRE 16 -1 (3375 1475)(3300 1475);
WIRE 16 -1 (3375 1300)(3375 1475);
WIRE 16 -1 (4200 1475)(3375 1475);
FORCEPROP 2 LAST SIG_NAME USB2_0_DP
J 0
(3440 1485);
DISPLAY 0.723404 (3440 1485);
PAINT WHITE (3440 1485);
WIRE 16 -1 (3475 1425)(3300 1425);
FORCEPROP 2 LAST SIG_NAME USB2_0_DN
J 0
(3440 1435);
DISPLAY 0.723404 (3440 1435);
PAINT WHITE (3440 1435);
WIRE 16 -1 (3475 1300)(3475 1425);
WIRE 16 -1 (4200 1425)(3475 1425);
WIRE 16 -1 (1250 1075)(1975 1075);
FORCEPROP 0 LAST SIG_NAME NC_USB_HUB_2_DP4
J 0
(1390 1085);
DISPLAY 0.723404 (1390 1085);
PAINT WHITE (1390 1085);
WIRE 16 -1 (-350 1475)(300 1475);
FORCEPROP 2 LAST SIG_NAME USB_HUB_2_DVDD
J 0
(-235 1485);
DISPLAY 0.638298 (-235 1485);
PAINT WHITE (-235 1485);
WIRE 16 -1 (-2800 2350)(-3000 2350);
FORCEPROP 2 LAST SIG_NAME P3V3_AUX_USB_HUB_2
J 0
(-2810 2360);
DISPLAY 0.510638 (-2810 2360);
PAINT WHITE (-2810 2360);
WIRE 16 -1 (-2800 2350)(-2800 2150);
WIRE 16 -1 (-2800 2350)(-2425 2350);
WIRE 16 -1 (-2425 2150)(-2425 2350);
WIRE 16 -1 (-2025 2350)(-2425 2350);
WIRE 16 -1 (-2025 2150)(-2025 2350);
WIRE 16 -1 (-1650 2350)(-2025 2350);
WIRE 16 -1 (-1650 2350)(-1650 2150);
WIRE 16 -1 (-1275 2350)(-1650 2350);
WIRE 16 -1 (-1275 2350)(-1275 2150);
WIRE 16 -1 (-900 2350)(-1275 2350);
WIRE 16 -1 (-900 2350)(-900 2150);
WIRE 16 -1 (-525 2350)(-900 2350);
WIRE 16 -1 (-525 2150)(-525 2350);
WIRE 16 -1 (-175 2350)(-525 2350);
WIRE 16 -1 (-175 2150)(-175 2350);
WIRE 16 -1 (150 2350)(-175 2350);
WIRE 16 -1 (300 1875)(150 1875);
WIRE 16 -1 (150 1875)(150 2350);
WIRE 16 -1 (150 1775)(150 1875);
WIRE 16 -1 (300 1775)(150 1775);
WIRE 16 -1 (150 1675)(150 1775);
WIRE 16 -1 (300 1675)(150 1675);
WIRE 16 -1 (150 1675)(150 1625);
WIRE 16 -1 (150 1625)(300 1625);
WIRE 16 -1 (150 1625)(150 1575);
WIRE 16 -1 (150 1575)(300 1575);
WIRE 16 -1 (-725 1575)(150 1575);
WIRE 16 -1 (-725 1475)(-725 1575);
WIRE 16 -1 (-550 1475)(-725 1475);
WIRE 16 -1 (3100 1425)(1250 1425);
FORCEPROP 2 LAST SIG_NAME USB2_PCH_0_R_DN
J 0
(1390 1435);
DISPLAY 0.723404 (1390 1435);
PAINT WHITE (1390 1435);
WIRE 16 -1 (300 1225)(-325 1225);
FORCEPROP 2 LAST SIG_NAME USB_HUB_2_OVCUR3
J 0
(-310 1235);
DISPLAY 0.723404 (-310 1235);
PAINT WHITE (-310 1235);
WIRE 16 -1 (300 1175)(-325 1175);
FORCEPROP 2 LAST SIG_NAME USB_HUB_2_OVCUR4
J 0
(-310 1185);
DISPLAY 0.723404 (-310 1185);
PAINT WHITE (-310 1185);
WIRE 16 -1 (-175 1950)(-175 1775);
WIRE 16 -1 (-525 1950)(-525 1775);
WIRE 16 -1 (-175 1775)(-525 1775);
WIRE 16 -1 (-900 1950)(-900 1775);
WIRE 16 -1 (-525 1775)(-900 1775);
WIRE 16 -1 (-1275 1950)(-1275 1775);
WIRE 16 -1 (-900 1775)(-1275 1775);
WIRE 16 -1 (-1650 1950)(-1650 1775);
WIRE 16 -1 (-1650 1775)(-1275 1775);
WIRE 16 -1 (-2025 1950)(-2025 1775);
WIRE 16 -1 (-2025 1775)(-1650 1775);
WIRE 16 -1 (-2425 1775)(-2025 1775);
WIRE 16 -1 (-2425 1950)(-2425 1775);
WIRE 16 -1 (-3200 2350)(-3350 2350);
WIRE 16 -1 (2275 1375)(1250 1375);
FORCEPROP 2 LAST SIG_NAME USB2_HUB_2_EXT_DP
J 0
(1390 1385);
DISPLAY 0.723404 (1390 1385);
PAINT WHITE (1390 1385);
WIRE 16 -1 (3100 1475)(1250 1475);
FORCEPROP 2 LAST SIG_NAME USB2_PCH_0_R_DP
J 0
(1390 1485);
DISPLAY 0.723404 (1390 1485);
PAINT WHITE (1390 1485);
WIRE 16 -1 (-100 875)(-100 725);
WIRE 16 -1 (300 875)(-100 875);
FORCEPROP 2 LAST SIG_NAME USB_HUB_2_PGANG
J 0
(-135 885);
DISPLAY 0.510638 (-135 885);
PAINT WHITE (-135 885);
WIRE 16 -1 (300 1325)(-325 1325);
FORCEPROP 2 LAST SIG_NAME USB_HUB_2_OVCUR1
J 0
(-310 1335);
DISPLAY 0.723404 (-310 1335);
PAINT WHITE (-310 1335);
WIRE 16 -1 (-225 -450)(-800 -450);
FORCEPROP 2 LAST SIG_NAME USB_HUB_2_OVCUR3
J 0
(-785 -440);
DISPLAY 0.723404 (-785 -440);
PAINT WHITE (-785 -440);
WIRE 16 -1 (-225 -575)(-800 -575);
FORCEPROP 2 LAST SIG_NAME USB_HUB_2_OVCUR4
J 0
(-785 -565);
DISPLAY 0.723404 (-785 -565);
PAINT WHITE (-785 -565);
WIRE 16 -1 (900 -2475)(1775 -2475);
FORCEPROP 2 LAST SIG_NAME TP_USB_HUB_2_ENA_HS
J 0
(1015 -2465);
DISPLAY 0.723404 (1015 -2465);
PAINT WHITE (1015 -2465);
WIRE 16 -1 (900 -2275)(2150 -2275);
FORCEPROP 2 LAST SIG_NAME USB2_HUB_2_BUF_EXT_R_DN
J 0
(1015 -2265);
DISPLAY 0.723404 (1015 -2265);
PAINT WHITE (1015 -2265);
FORCEPROP 2 LASTPROP $XR0 196 
J 0
(799 -2265);
DISPLAY 0.638298 (799 -2265);
PAINT MONO (799 -2265);
WIRE 16 -1 (1250 1825)(2025 1825);
FORCEPROP 0 LAST SIG_NAME USB_HUB_2_TEST
J 0
(1315 1835);
DISPLAY 0.723404 (1315 1835);
PAINT WHITE (1315 1835);
WIRE 16 -1 (1250 1875)(1925 1875);
FORCEPROP 0 LAST SIG_NAME NC_USB_HUB_2_SDA
J 0
(1315 1885);
DISPLAY 0.723404 (1315 1885);
PAINT WHITE (1315 1885);
WIRE 16 -1 (300 1275)(-325 1275);
FORCEPROP 2 LAST SIG_NAME USB_HUB_2_OVCUR2
J 0
(-310 1285);
DISPLAY 0.723404 (-310 1285);
PAINT WHITE (-310 1285);
WIRE 16 -1 (2350 -2225)(3925 -2225);
FORCEPROP 2 LAST SIG_NAME USB2_HUB_2_BUF_EXT_DP
J 0
(2990 -2215);
DISPLAY 0.723404 (2990 -2215);
PAINT WHITE (2990 -2215);
WIRE 16 -1 (900 -2225)(2150 -2225);
FORCEPROP 2 LAST SIG_NAME USB2_HUB_2_BUF_EXT_R_DP
J 0
(1015 -2215);
DISPLAY 0.723404 (1015 -2215);
PAINT WHITE (1015 -2215);
FORCEPROP 2 LASTPROP $XR0 196 
J 0
(799 -2215);
DISPLAY 0.638298 (799 -2215);
PAINT MONO (799 -2215);
WIRE 16 -1 (2350 -2275)(3925 -2275);
FORCEPROP 2 LAST SIG_NAME USB2_HUB_2_BUF_EXT_DN
J 0
(2990 -2265);
DISPLAY 0.723404 (2990 -2265);
PAINT WHITE (2990 -2265);
WIRE 16 -1 (-25 -2475)(-25 -2600);
WIRE 16 -1 (150 -2475)(-25 -2475);
FORCEPROP 2 LAST SIG_NAME PD_USB_HUB_2_EQ
J 0
(-485 -2475);
DISPLAY 0.723404 (-485 -2475);
PAINT WHITE (-485 -2475);
WIRE 16 -1 (-225 -175)(-800 -175);
FORCEPROP 2 LAST SIG_NAME USB_HUB_2_OVCUR1
J 0
(-785 -165);
DISPLAY 0.723404 (-785 -165);
PAINT WHITE (-785 -165);
WIRE 16 -1 (-225 -325)(-800 -325);
FORCEPROP 2 LAST SIG_NAME USB_HUB_2_OVCUR2
J 0
(-785 -315);
DISPLAY 0.723404 (-785 -315);
PAINT WHITE (-785 -315);
WIRE 16 -1 (900 -2425)(2025 -2425);
WIRE 16 -1 (-725 -2375)(150 -2375);
FORCEPROP 2 LAST SIG_NAME TP_USB_HUB_2_CD
J 0
(-485 -2365);
DISPLAY 0.723404 (-485 -2365);
PAINT WHITE (-485 -2365);
WIRE 16 -1 (-725 -2325)(150 -2325);
FORCEPROP 2 LAST SIG_NAME TP_USB_HUB_2_TEST
J 0
(-485 -2315);
DISPLAY 0.723404 (-485 -2315);
PAINT WHITE (-485 -2315);
WIRE 16 -1 (-2850 -2275)(-1650 -2275);
FORCEPROP 2 LAST SIG_NAME USB2_HUB_2_EXT_DN
J 0
(-2835 -2265);
DISPLAY 0.723404 (-2835 -2265);
PAINT WHITE (-2835 -2265);
WIRE 16 -1 (1250 1025)(1975 1025);
FORCEPROP 0 LAST SIG_NAME NC_USB_HUB_2_DM4
J 0
(1390 1035);
DISPLAY 0.723404 (1390 1035);
PAINT WHITE (1390 1035);
WIRE 16 -1 (1250 1125)(1975 1125);
FORCEPROP 0 LAST SIG_NAME NC_USB_HUB_2_DM3
J 0
(1390 1135);
DISPLAY 0.723404 (1390 1135);
PAINT WHITE (1390 1135);
WIRE 16 -1 (300 925)(-175 925);
FORCEPROP 2 LAST SIG_NAME USB_HUB_2_PSELF
J 0
(-135 935);
DISPLAY 0.510638 (-135 935);
PAINT WHITE (-135 935);
WIRE 16 -1 (-1000 -175)(-1525 -175);
WIRE 16 -1 (-1525 -175)(-1525 -325);
WIRE 16 -1 (-1000 -325)(-1525 -325);
WIRE 16 -1 (-1525 -325)(-1525 -450);
WIRE 16 -1 (-1000 -450)(-1525 -450);
WIRE 16 -1 (-1525 -450)(-1525 -575);
WIRE 16 -1 (-1525 -575)(-1000 -575);
DOT 1 (-1250 925);
DOT 1 (-1650 1775);
DOT 1 (-900 1775);
DOT 1 (-525 1775);
DOT 1 (-1275 2350);
DOT 1 (-2025 2350);
DOT 1 (-1275 -2275);
DOT 1 (-1350 -2225);
DOT 1 (-1250 975);
DOT 1 (-2800 2350);
DOT 1 (-2425 2350);
DOT 1 (-1650 2350);
DOT 1 (-900 2350);
DOT 1 (-525 2350);
DOT 1 (-175 2350);
DOT 1 (3375 1475);
DOT 1 (3475 1425);
DOT 1 (4125 2175);
DOT 1 (5125 2175);
DOT 1 (-3500 175);
DOT 1 (-1625 475);
DOT 1 (150 1625);
DOT 1 (150 1675);
DOT 1 (150 1775);
DOT 1 (-2425 1775);
DOT 1 (-2025 1775);
DOT 1 (-1275 1775);
DOT 1 (150 1875);
DOT 1 (1375 -1950);
DOT 1 (1375 -1550);
DOT 1 (-1275 -1275);
DOT 1 (-1525 -450);
DOT 1 (-1525 -325);
DOT 1 (-1525 -175);
DOT 1 (-2800 1775);
DOT 1 (1800 -1550);
DOT 1 (150 1575);
DOT 1 (-1350 -1225);
FORCENOTE
USB_HUB_I2C ONLY FOR EEPROM.
(1450 2050) 0;
DISPLAY LEFT (1450 2050);
DISPLAY 0.808511 (1450 2050);
PAINT WHITE (1450 2050);
FORCENOTE
20211208 MODIFY FOR GT
(-3800 2825) 0;
DISPLAY LEFT (-3800 2825);
DISPLAY 2.510638 (-3800 2825);
PAINT PINK (-3800 2825);
FORCENOTE
$CDS_IMAGE|clipboard_0_7.jpg|1350|1027
(4250 -1475) 0;
DISPLAY LEFT (4250 -1475);
QUIT
